FILE_TYPE = MACRO_DRAWING;
SET COLOR_WIRE YELLOW;
SET COLOR_PROP MONO;
SET COLOR_DOT WHITE;
SET COLOR_ARC YELLOW;
SET COLOR_BODY GREEN;
SET COLOR_NOTE MONO;
SET PROP_DISPLAY VALUE;
SET PAGE_NUMBER P108;
FORCEADD CAP_A..1
(-3275 675);
FORCEPROP 1 LAST PART_NUMBER A36096-030
J 0
(-3225 525);
DISPLAY 0.617021 (-3225 525);
PAINT BLUE (-3225 525);
FORCEPROP 1 LAST LOCATION C2U20
J 0
(-3225 775);
DISPLAY 0.617021 (-3225 775);
PAINT AQUA (-3225 775);
FORCEPROP 1 LASTPIN (-3275 775) $PN 1
J 0
(-3265 755);
DISPLAY 0.617021 (-3265 755);
PAINT ORANGE (-3265 755);
FORCEPROP 1 LAST VALUE 0.1UF
J 0
(-3225 725);
DISPLAY 0.617021 (-3225 725);
PAINT SKYBLUE (-3225 725);
FORCEPROP 1 LAST TOLERANCE 10%
J 0
(-3225 625);
DISPLAY 0.617021 (-3225 625);
PAINT SKYBLUE (-3225 625);
FORCEPROP 1 LAST VOLTAGE 16V
J 0
(-3225 675);
DISPLAY 0.617021 (-3225 675);
PAINT SKYBLUE (-3225 675);
FORCEPROP 1 LAST MATERIAL X7R
J 0
(-3225 575);
DISPLAY 0.617021 (-3225 575);
PAINT SKYBLUE (-3225 575);
FORCEPROP 1 LASTPIN (-3275 575) $PN 2
J 0
(-3265 555);
DISPLAY 0.617021 (-3265 555);
PAINT ORANGE (-3265 555);
FORCEPROP 1 LAST PACK_TYPE 0402V
J 0
(-3225 475);
DISPLAY 0.617021 (-3225 475);
PAINT SKYBLUE (-3225 475);
FORCEPROP 0 LAST ROOM IO_SLOT
J 0
(-3225 875);
DISPLAY 1.021277 (-3225 875);
PAINT ORANGE (-3225 875);
DISPLAY INVISIBLE (-3225 875);
FORCEPROP 2 LAST SEC_TYPE 0402V
J 0
(-3225 875);
DISPLAY 1.021277 (-3225 875);
PAINT ORANGE (-3225 875);
DISPLAY INVISIBLE (-3225 875);
FORCEPROP 2 LAST SEC 1
J 0
(-3225 875);
DISPLAY 0.680851 (-3225 875);
PAINT MONO (-3225 875);
DISPLAY INVISIBLE (-3225 875);
FORCEPROP 2 LAST CDS_LOCATION C2U20
J 0
(-3225 775);
DISPLAY 0.617021 (-3225 775);
PAINT AQUA (-3225 775);
DISPLAY INVISIBLE (-3225 775);
FORCEPROP 1 LAST PATH I1
J 0
(-3225 825);
DISPLAY 0.978723 (-3225 825);
PAINT WHITE (-3225 825);
DISPLAY INVISIBLE (-3225 825);
FORCEPROP 2 LAST CDS_SEC 1
J 0
(-3225 825);
PAINT ORANGE (-3225 825);
DISPLAY INVISIBLE (-3225 825);
FORCEPROP 2 LAST CDS_LIB dev_discrete
J 0
(-3275 675);
PAINT ORANGE (-3275 675);
DISPLAY INVISIBLE (-3275 675);
FORCEADD P12V..1
(1375 4675);
FORCEPROP 3 LASTPIN (1375 4625) SIG_NAME P12V\g
J 0
(1385 4635);
DISPLAY 0.659574 (1385 4635);
PAINT MONO (1385 4635);
DISPLAY INVISIBLE (1385 4635);
FORCEPROP 1 LAST VOLTAGE +12.
J 0
(1375 4675);
PAINT SKYBLUE (1375 4675);
DISPLAY INVISIBLE (1375 4675);
FORCEPROP 1 LAST PATH I165
J 0
(1420 4677);
DISPLAY 0.340426 (1420 4677);
PAINT GREEN (1420 4677);
DISPLAY INVISIBLE (1420 4677);
FORCEPROP 1 LAST BODY_TYPE PLUMBING
J 0
(1330 4632);
DISPLAY 0.255319 (1330 4632);
PAINT GREEN (1330 4632);
DISPLAY INVISIBLE (1330 4632);
FORCEPROP 2 LAST CDS_LIB mstr_symbols
J 0
(1375 4675);
PAINT ORANGE (1375 4675);
DISPLAY INVISIBLE (1375 4675);
FORCEPROP 1 LAST SIZE 1B
J 0
(1420 4697);
DISPLAY 0.255319 (1420 4697);
PAINT GREEN (1420 4697);
DISPLAY INVISIBLE (1420 4697);
FORCEPROP 1 LAST HDL_POWER P12V
J 0
(1175 4525);
DISPLAY 0.638298 (1175 4525);
PAINT GREEN (1175 4525);
DISPLAY INVISIBLE (1175 4525);
FORCEADD P12V..1
(-350 4725);
FORCEPROP 3 LASTPIN (-350 4675) SIG_NAME P12V\g
J 0
(-340 4685);
DISPLAY 0.659574 (-340 4685);
PAINT MONO (-340 4685);
DISPLAY INVISIBLE (-340 4685);
FORCEPROP 1 LAST VOLTAGE +12.
J 0
(-350 4725);
PAINT SKYBLUE (-350 4725);
DISPLAY INVISIBLE (-350 4725);
FORCEPROP 1 LAST SIZE 1B
J 0
(-305 4747);
DISPLAY 0.255319 (-305 4747);
PAINT GREEN (-305 4747);
DISPLAY INVISIBLE (-305 4747);
FORCEPROP 2 LAST CDS_LIB mstr_symbols
J 0
(-350 4725);
PAINT ORANGE (-350 4725);
DISPLAY INVISIBLE (-350 4725);
FORCEPROP 1 LAST BODY_TYPE PLUMBING
J 0
(-395 4682);
DISPLAY 0.255319 (-395 4682);
PAINT GREEN (-395 4682);
DISPLAY INVISIBLE (-395 4682);
FORCEPROP 1 LAST PATH I167
J 0
(-305 4727);
DISPLAY 0.340426 (-305 4727);
PAINT GREEN (-305 4727);
DISPLAY INVISIBLE (-305 4727);
FORCEPROP 1 LAST HDL_POWER P12V
J 0
(-550 4575);
DISPLAY 0.638298 (-550 4575);
PAINT GREEN (-550 4575);
DISPLAY INVISIBLE (-550 4575);
FORCEADD GND..1
(-100 1225);
FORCEPROP 3 LASTPIN (-100 1275) SIG_NAME GND\g
J 0
(-90 1285);
DISPLAY 0.659574 (-90 1285);
PAINT MONO (-90 1285);
DISPLAY INVISIBLE (-90 1285);
FORCEPROP 1 LAST HDL_POWER GND
J 0
(-100 1375);
DISPLAY 0.638298 (-100 1375);
PAINT GREEN (-100 1375);
DISPLAY INVISIBLE (-100 1375);
FORCEPROP 1 LAST PATH I168
J 0
(-25 1225);
DISPLAY 0.872340 (-25 1225);
PAINT AQUA (-25 1225);
DISPLAY INVISIBLE (-25 1225);
FORCEPROP 1 LAST BODY_TYPE PLUMBING
J 0
(-145 1182);
DISPLAY 0.340426 (-145 1182);
PAINT GREEN (-145 1182);
DISPLAY INVISIBLE (-145 1182);
FORCEPROP 1 LAST SIZE 1B
J 0
(-25 1175);
DISPLAY 0.638298 (-25 1175);
PAINT GREEN (-25 1175);
DISPLAY INVISIBLE (-25 1175);
FORCEPROP 2 LAST CDS_LIB mstr_symbols
J 0
(-100 1225);
PAINT ORANGE (-100 1225);
DISPLAY INVISIBLE (-100 1225);
FORCEPROP 1 LAST VOLTAGE 0
J 0
(-100 1225);
PAINT SKYBLUE (-100 1225);
DISPLAY INVISIBLE (-100 1225);
FORCEADD P3V3..1
(-525 4625);
FORCEPROP 3 LASTPIN (-525 4575) SIG_NAME P3V3\g
J 0
(-515 4585);
DISPLAY 0.659574 (-515 4585);
PAINT MONO (-515 4585);
DISPLAY INVISIBLE (-515 4585);
FORCEPROP 1 LAST SIZE 1B
J 0
(-480 4647);
DISPLAY 0.340426 (-480 4647);
PAINT GREEN (-480 4647);
DISPLAY INVISIBLE (-480 4647);
FORCEPROP 1 LAST PATH I172
J 0
(-480 4627);
DISPLAY 0.340426 (-480 4627);
PAINT GREEN (-480 4627);
DISPLAY INVISIBLE (-480 4627);
FORCEPROP 1 LAST VOLTAGE 3.3V
J 0
(-570 4582);
DISPLAY 0.340426 (-570 4582);
PAINT SKYBLUE (-570 4582);
DISPLAY INVISIBLE (-570 4582);
FORCEPROP 2 LAST CDS_LIB mstr_symbols
J 0
(-525 4625);
PAINT ORANGE (-525 4625);
DISPLAY INVISIBLE (-525 4625);
FORCEPROP 1 LAST BODY_TYPE PLUMBING
J 0
(-570 4582);
DISPLAY 0.340426 (-570 4582);
PAINT GREEN (-570 4582);
DISPLAY INVISIBLE (-570 4582);
FORCEPROP 1 LAST HDL_POWER P3V3
J 0
(-850 4500);
DISPLAY 0.872340 (-850 4500);
PAINT ORANGE (-850 4500);
DISPLAY INVISIBLE (-850 4500);
FORCEADD RES..1
(-625 3625);
FORCEPROP 1 LAST PART_NUMBER G21497-005
J 0
(-1150 3575);
DISPLAY 0.617021 (-1150 3575);
PAINT BLUE (-1150 3575);
FORCEPROP 1 LAST VALUE 0.0
J 2
(-675 3575);
DISPLAY 0.617021 (-675 3575);
PAINT SKYBLUE (-675 3575);
FORCEPROP 1 LAST WATTAGE 1/16W
J 2
(-775 3575);
DISPLAY 0.617021 (-775 3575);
PAINT SKYBLUE (-775 3575);
FORCEPROP 1 LAST PACK_TYPE 0402
J 0
(-400 3575);
DISPLAY 0.617021 (-400 3575);
PAINT SKYBLUE (-400 3575);
FORCEPROP 1 LAST MATERIAL CHIP
J 0
(-525 3575);
DISPLAY 0.617021 (-525 3575);
PAINT SKYBLUE (-525 3575);
FORCEPROP 1 LASTPIN (-525 3625) $PN 2
J 0
(-563 3637);
DISPLAY 0.617021 (-563 3637);
PAINT ORANGE (-563 3637);
FORCEPROP 1 LAST LOCATION R2U37
J 0
(-675 3675);
DISPLAY 0.617021 (-675 3675);
PAINT AQUA (-675 3675);
FORCEPROP 1 LASTPIN (-725 3625) $PN 1
J 0
(-713 3637);
DISPLAY 0.617021 (-713 3637);
PAINT ORANGE (-713 3637);
FORCEPROP 1 LAST TOLERANCE 5%
J 0
(-625 3575);
DISPLAY 0.617021 (-625 3575);
PAINT SKYBLUE (-625 3575);
FORCEPROP 2 LAST SEC_TYPE 0402
J 0
(-675 3825);
DISPLAY 1.021277 (-675 3825);
PAINT ORANGE (-675 3825);
DISPLAY INVISIBLE (-675 3825);
FORCEPROP 2 LAST SEC 1
J 0
(-675 3825);
DISPLAY 0.680851 (-675 3825);
PAINT MONO (-675 3825);
DISPLAY INVISIBLE (-675 3825);
FORCEPROP 0 LAST ROOM IO_SLOT
J 0
(-675 3825);
DISPLAY 1.021277 (-675 3825);
PAINT ORANGE (-675 3825);
DISPLAY INVISIBLE (-675 3825);
FORCEPROP 2 LAST CDS_LIB mstr_discrete
J 0
(-625 3625);
PAINT MONO (-625 3625);
DISPLAY INVISIBLE (-625 3625);
FORCEPROP 1 LAST PATH I173
J 0
(-675 3775);
DISPLAY 0.978723 (-675 3775);
PAINT WHITE (-675 3775);
DISPLAY INVISIBLE (-675 3775);
FORCEPROP 2 LAST CDS_LOCATION R2U37
J 0
(-675 3675);
DISPLAY 0.617021 (-675 3675);
PAINT AQUA (-675 3675);
DISPLAY INVISIBLE (-675 3675);
FORCEADD OFFPAGE..1
(-1525 3625);
FORCEPROP 2 LAST $XR0 190 
J 0
(-1807 3625);
DISPLAY 0.638298 (-1807 3625);
PAINT MONO (-1807 3625);
FORCEPROP 2 LAST CDS_LIB mstr_standard
J 0
(-1525 3625);
PAINT ORANGE (-1525 3625);
DISPLAY INVISIBLE (-1525 3625);
FORCEPROP 2 LAST PATH I174
J 0
(-1475 3700);
DISPLAY 1.021277 (-1475 3700);
PAINT ORANGE (-1475 3700);
DISPLAY INVISIBLE (-1475 3700);
FORCEPROP 1 LAST OFFPAGE TRUE
J 0
(-1200 3500);
DISPLAY 0.872340 (-1200 3500);
PAINT GREEN (-1200 3500);
DISPLAY INVISIBLE (-1200 3500);
FORCEPROP 1 LAST COMMENT_BODY TRUE
J 0
(-1400 3525);
DISPLAY 0.872340 (-1400 3525);
PAINT GREEN (-1400 3525);
DISPLAY INVISIBLE (-1400 3525);
FORCEADD OFFPAGE..1
(-1525 3375);
FORCEPROP 2 LAST $XR0 114 
J 0
(-1777 3375);
DISPLAY 0.638298 (-1777 3375);
PAINT MONO (-1777 3375);
FORCEPROP 1 LAST OFFPAGE TRUE
J 0
(-1200 3250);
DISPLAY 0.872340 (-1200 3250);
PAINT GREEN (-1200 3250);
DISPLAY INVISIBLE (-1200 3250);
FORCEPROP 2 LAST PATH I175
J 0
(-1475 3450);
DISPLAY 1.021277 (-1475 3450);
PAINT ORANGE (-1475 3450);
DISPLAY INVISIBLE (-1475 3450);
FORCEPROP 2 LAST CDS_LIB mstr_standard
J 0
(-1525 3375);
PAINT ORANGE (-1525 3375);
DISPLAY INVISIBLE (-1525 3375);
FORCEPROP 1 LAST COMMENT_BODY TRUE
J 0
(-1400 3275);
DISPLAY 0.872340 (-1400 3275);
PAINT GREEN (-1400 3275);
DISPLAY INVISIBLE (-1400 3275);
FORCEADD OFFPAGE..1
(-1525 3325);
FORCEPROP 2 LAST $XR0 114 
J 0
(-1777 3325);
DISPLAY 0.638298 (-1777 3325);
PAINT MONO (-1777 3325);
FORCEPROP 1 LAST OFFPAGE TRUE
J 0
(-1200 3200);
DISPLAY 0.872340 (-1200 3200);
PAINT GREEN (-1200 3200);
DISPLAY INVISIBLE (-1200 3200);
FORCEPROP 2 LAST PATH I176
J 0
(-1475 3400);
DISPLAY 1.021277 (-1475 3400);
PAINT ORANGE (-1475 3400);
DISPLAY INVISIBLE (-1475 3400);
FORCEPROP 2 LAST CDS_LIB mstr_standard
J 0
(-1525 3325);
PAINT ORANGE (-1525 3325);
DISPLAY INVISIBLE (-1525 3325);
FORCEPROP 1 LAST COMMENT_BODY TRUE
J 0
(-1400 3225);
DISPLAY 0.872340 (-1400 3225);
PAINT GREEN (-1400 3225);
DISPLAY INVISIBLE (-1400 3225);
FORCEADD CAP_A..1
(-2875 650);
FORCEPROP 1 LAST PART_NUMBER A36096-030
J 0
(-2825 500);
DISPLAY 0.617021 (-2825 500);
PAINT BLUE (-2825 500);
FORCEPROP 1 LAST LOCATION C2U24
J 0
(-2825 750);
DISPLAY 0.617021 (-2825 750);
PAINT AQUA (-2825 750);
FORCEPROP 1 LAST VALUE 0.1UF
J 0
(-2825 700);
DISPLAY 0.617021 (-2825 700);
PAINT SKYBLUE (-2825 700);
FORCEPROP 1 LAST TOLERANCE 10%
J 0
(-2825 600);
DISPLAY 0.617021 (-2825 600);
PAINT SKYBLUE (-2825 600);
FORCEPROP 1 LAST VOLTAGE 16V
J 0
(-2825 650);
DISPLAY 0.617021 (-2825 650);
PAINT SKYBLUE (-2825 650);
FORCEPROP 1 LAST MATERIAL X7R
J 0
(-2825 550);
DISPLAY 0.617021 (-2825 550);
PAINT SKYBLUE (-2825 550);
FORCEPROP 1 LASTPIN (-2875 750) $PN 1
J 0
(-2865 730);
DISPLAY 0.617021 (-2865 730);
PAINT ORANGE (-2865 730);
FORCEPROP 1 LASTPIN (-2875 550) $PN 2
J 0
(-2865 530);
DISPLAY 0.617021 (-2865 530);
PAINT ORANGE (-2865 530);
FORCEPROP 1 LAST PACK_TYPE 0402V
J 0
(-2825 450);
DISPLAY 0.617021 (-2825 450);
PAINT SKYBLUE (-2825 450);
FORCEPROP 0 LAST ROOM IO_SLOT
J 0
(-2825 850);
DISPLAY 1.021277 (-2825 850);
PAINT ORANGE (-2825 850);
DISPLAY INVISIBLE (-2825 850);
FORCEPROP 1 LAST PATH I2
J 0
(-2825 800);
DISPLAY 0.978723 (-2825 800);
PAINT WHITE (-2825 800);
DISPLAY INVISIBLE (-2825 800);
FORCEPROP 2 LAST CDS_SEC 1
J 0
(-2825 800);
PAINT ORANGE (-2825 800);
DISPLAY INVISIBLE (-2825 800);
FORCEPROP 2 LAST SEC_TYPE 0402V
J 0
(-2825 850);
DISPLAY 1.021277 (-2825 850);
PAINT ORANGE (-2825 850);
DISPLAY INVISIBLE (-2825 850);
FORCEPROP 2 LAST SEC 1
J 0
(-2825 850);
DISPLAY 0.680851 (-2825 850);
PAINT MONO (-2825 850);
DISPLAY INVISIBLE (-2825 850);
FORCEPROP 2 LAST CDS_LOCATION C2U24
J 0
(-2825 750);
DISPLAY 0.617021 (-2825 750);
PAINT AQUA (-2825 750);
DISPLAY INVISIBLE (-2825 750);
FORCEPROP 2 LAST CDS_LIB dev_discrete
J 0
(-2875 650);
PAINT ORANGE (-2875 650);
DISPLAY INVISIBLE (-2875 650);
FORCEADD GND..1
(1050 1225);
FORCEPROP 3 LASTPIN (1050 1275) SIG_NAME GND\g
J 0
(1060 1285);
DISPLAY 0.659574 (1060 1285);
PAINT MONO (1060 1285);
DISPLAY INVISIBLE (1060 1285);
FORCEPROP 1 LAST VOLTAGE 0
J 0
(1050 1225);
PAINT SKYBLUE (1050 1225);
DISPLAY INVISIBLE (1050 1225);
FORCEPROP 1 LAST SIZE 1B
J 0
(1125 1175);
DISPLAY 0.638298 (1125 1175);
PAINT GREEN (1125 1175);
DISPLAY INVISIBLE (1125 1175);
FORCEPROP 2 LAST CDS_LIB mstr_symbols
J 0
(1050 1225);
PAINT ORANGE (1050 1225);
DISPLAY INVISIBLE (1050 1225);
FORCEPROP 1 LAST PATH I236
J 0
(1125 1225);
DISPLAY 0.872340 (1125 1225);
PAINT AQUA (1125 1225);
DISPLAY INVISIBLE (1125 1225);
FORCEPROP 1 LAST HDL_POWER GND
J 0
(1050 1375);
DISPLAY 0.638298 (1050 1375);
PAINT GREEN (1050 1375);
DISPLAY INVISIBLE (1050 1375);
FORCEPROP 1 LAST BODY_TYPE PLUMBING
J 0
(1005 1182);
DISPLAY 0.340426 (1005 1182);
PAINT GREEN (1005 1182);
DISPLAY INVISIBLE (1005 1182);
FORCEADD P3V3..1
(1600 4675);
FORCEPROP 3 LASTPIN (1600 4625) SIG_NAME P3V3\g
J 0
(1610 4635);
DISPLAY 0.659574 (1610 4635);
PAINT MONO (1610 4635);
DISPLAY INVISIBLE (1610 4635);
FORCEPROP 1 LAST VOLTAGE 3.3V
J 0
(1555 4632);
DISPLAY 0.340426 (1555 4632);
PAINT SKYBLUE (1555 4632);
DISPLAY INVISIBLE (1555 4632);
FORCEPROP 1 LAST SIZE 1B
J 0
(1645 4697);
DISPLAY 0.340426 (1645 4697);
PAINT GREEN (1645 4697);
DISPLAY INVISIBLE (1645 4697);
FORCEPROP 2 LAST CDS_LIB mstr_symbols
J 0
(1600 4675);
PAINT ORANGE (1600 4675);
DISPLAY INVISIBLE (1600 4675);
FORCEPROP 1 LAST BODY_TYPE PLUMBING
J 0
(1555 4632);
DISPLAY 0.340426 (1555 4632);
PAINT GREEN (1555 4632);
DISPLAY INVISIBLE (1555 4632);
FORCEPROP 1 LAST PATH I238
J 0
(1645 4677);
DISPLAY 0.340426 (1645 4677);
PAINT GREEN (1645 4677);
DISPLAY INVISIBLE (1645 4677);
FORCEPROP 1 LAST HDL_POWER P3V3
J 0
(1275 4550);
DISPLAY 0.872340 (1275 4550);
PAINT ORANGE (1275 4550);
DISPLAY INVISIBLE (1275 4550);
FORCEADD OFFPAGE..2
(2850 3975);
FORCEPROP 2 LAST $XR2 146 
J 0
(3279 3975);
DISPLAY 0.638298 (3279 3975);
PAINT MONO (3279 3975);
FORCEPROP 2 LAST $XR1 119 
J 0
(3159 3975);
DISPLAY 0.638298 (3159 3975);
PAINT MONO (3159 3975);
FORCEPROP 2 LAST $XR0 157 
J 0
(3039 3975);
DISPLAY 0.638298 (3039 3975);
PAINT MONO (3039 3975);
FORCEPROP 1 LAST OFFPAGE TRUE
J 0
(3175 3850);
DISPLAY 0.872340 (3175 3850);
PAINT GREEN (3175 3850);
DISPLAY INVISIBLE (3175 3850);
FORCEPROP 2 LAST PATH I243
J 0
(3025 4050);
DISPLAY 1.021277 (3025 4050);
PAINT ORANGE (3025 4050);
DISPLAY INVISIBLE (3025 4050);
FORCEPROP 2 LAST CDS_LIB mstr_standard
J 0
(2850 3975);
PAINT ORANGE (2850 3975);
DISPLAY INVISIBLE (2850 3975);
FORCEPROP 1 LAST COMMENT_BODY TRUE
J 0
(2805 3880);
DISPLAY 0.872340 (2805 3880);
PAINT GREEN (2805 3880);
DISPLAY INVISIBLE (2805 3880);
FORCEADD GND..1
(-2875 300);
FORCEPROP 3 LASTPIN (-2875 350) SIG_NAME GND\g
J 0
(-2865 360);
DISPLAY 0.659574 (-2865 360);
PAINT MONO (-2865 360);
DISPLAY INVISIBLE (-2865 360);
FORCEPROP 1 LAST PATH I250
J 0
(-2800 300);
DISPLAY 0.872340 (-2800 300);
PAINT AQUA (-2800 300);
DISPLAY INVISIBLE (-2800 300);
FORCEPROP 1 LAST SIZE 1B
J 0
(-2800 250);
DISPLAY 0.872340 (-2800 250);
PAINT AQUA (-2800 250);
DISPLAY INVISIBLE (-2800 250);
FORCEPROP 1 LAST HDL_POWER GND
J 0
(-2875 450);
DISPLAY 0.872340 (-2875 450);
PAINT GREEN (-2875 450);
DISPLAY INVISIBLE (-2875 450);
FORCEPROP 1 LAST VOLTAGE 0
J 0
(-2875 300);
PAINT SKYBLUE (-2875 300);
DISPLAY INVISIBLE (-2875 300);
FORCEPROP 2 LAST CDS_LIB mstr_symbols
J 0
(-2875 300);
PAINT ORANGE (-2875 300);
DISPLAY INVISIBLE (-2875 300);
FORCEPROP 1 LAST BODY_TYPE PLUMBING
J 0
(-2920 257);
DISPLAY 0.340426 (-2920 257);
PAINT GREEN (-2920 257);
DISPLAY INVISIBLE (-2920 257);
FORCEADD P3V3..1
(-3275 1650);
FORCEPROP 3 LASTPIN (-3275 1600) SIG_NAME P3V3\g
J 0
(-3265 1610);
DISPLAY 0.659574 (-3265 1610);
PAINT MONO (-3265 1610);
DISPLAY INVISIBLE (-3265 1610);
FORCEPROP 1 LAST SIZE 1B
J 0
(-3230 1672);
DISPLAY 0.340426 (-3230 1672);
PAINT GREEN (-3230 1672);
DISPLAY INVISIBLE (-3230 1672);
FORCEPROP 2 LAST CDS_LIB mstr_symbols
J 0
(-3275 1650);
PAINT ORANGE (-3275 1650);
DISPLAY INVISIBLE (-3275 1650);
FORCEPROP 1 LAST PATH I251
J 0
(-3230 1652);
DISPLAY 0.340426 (-3230 1652);
PAINT GREEN (-3230 1652);
DISPLAY INVISIBLE (-3230 1652);
FORCEPROP 1 LAST BODY_TYPE PLUMBING
J 0
(-3320 1607);
DISPLAY 0.340426 (-3320 1607);
PAINT GREEN (-3320 1607);
DISPLAY INVISIBLE (-3320 1607);
FORCEPROP 1 LAST VOLTAGE 3.3V
J 0
(-3320 1607);
DISPLAY 0.340426 (-3320 1607);
PAINT SKYBLUE (-3320 1607);
DISPLAY INVISIBLE (-3320 1607);
FORCEPROP 1 LAST HDL_POWER P3V3
J 0
(-3600 1525);
DISPLAY 0.872340 (-3600 1525);
PAINT ORANGE (-3600 1525);
DISPLAY INVISIBLE (-3600 1525);
FORCEADD GND..1
(-2875 975);
FORCEPROP 3 LASTPIN (-2875 1025) SIG_NAME GND\g
J 0
(-2865 1035);
DISPLAY 0.659574 (-2865 1035);
PAINT MONO (-2865 1035);
DISPLAY INVISIBLE (-2865 1035);
FORCEPROP 1 LAST HDL_POWER GND
J 0
(-2875 1125);
DISPLAY 0.872340 (-2875 1125);
PAINT GREEN (-2875 1125);
DISPLAY INVISIBLE (-2875 1125);
FORCEPROP 1 LAST PATH I252
J 0
(-2800 975);
DISPLAY 0.872340 (-2800 975);
PAINT AQUA (-2800 975);
DISPLAY INVISIBLE (-2800 975);
FORCEPROP 1 LAST SIZE 1B
J 0
(-2800 925);
DISPLAY 0.872340 (-2800 925);
PAINT AQUA (-2800 925);
DISPLAY INVISIBLE (-2800 925);
FORCEPROP 1 LAST VOLTAGE 0
J 0
(-2875 975);
PAINT SKYBLUE (-2875 975);
DISPLAY INVISIBLE (-2875 975);
FORCEPROP 2 LAST CDS_LIB mstr_symbols
J 0
(-2875 975);
PAINT ORANGE (-2875 975);
DISPLAY INVISIBLE (-2875 975);
FORCEPROP 1 LAST BODY_TYPE PLUMBING
J 0
(-2920 932);
DISPLAY 0.340426 (-2920 932);
PAINT GREEN (-2920 932);
DISPLAY INVISIBLE (-2920 932);
FORCEADD SCONN200_H68296001..1
(500 3075);
FORCEPROP 2 LASTPIN (200 3475) $PN 35
J 2
(190 3485);
DISPLAY 0.617021 (190 3485);
PAINT ORANGE (190 3485);
FORCEPROP 2 LASTPIN (200 3525) $PN 33
J 2
(190 3535);
DISPLAY 0.617021 (190 3535);
PAINT ORANGE (190 3535);
FORCEPROP 2 LASTPIN (200 3425) $PN 37
J 2
(190 3435);
DISPLAY 0.617021 (190 3435);
PAINT ORANGE (190 3435);
FORCEPROP 2 LASTPIN (800 4175) $PN 8
J 0
(810 4185);
DISPLAY 0.617021 (810 4185);
PAINT ORANGE (810 4185);
FORCEPROP 2 LASTPIN (800 4225) $PN 6
J 0
(810 4235);
DISPLAY 0.617021 (810 4235);
PAINT ORANGE (810 4235);
FORCEPROP 2 LASTPIN (800 4275) $PN 4
J 0
(810 4285);
DISPLAY 0.617021 (810 4285);
PAINT ORANGE (810 4285);
FORCEPROP 2 LASTPIN (800 4325) $PN 2
J 0
(810 4335);
DISPLAY 0.617021 (810 4335);
PAINT ORANGE (810 4335);
FORCEPROP 2 LASTPIN (800 4125) $PN 10
J 0
(810 4135);
DISPLAY 0.617021 (810 4135);
PAINT ORANGE (810 4135);
FORCEPROP 1 LAST MATERIAL CONN
J 0
(250 4525);
DISPLAY 0.617021 (250 4525);
PAINT SKYBLUE (250 4525);
FORCEPROP 1 LAST LOCATION J8G1
J 0
(225 4575);
DISPLAY 0.617021 (225 4575);
PAINT AQUA (225 4575);
FORCEPROP 2 LASTPIN (200 4325) $PN 1
J 2
(190 4335);
DISPLAY 0.617021 (190 4335);
PAINT ORANGE (190 4335);
FORCEPROP 2 LASTPIN (200 4275) $PN 3
J 2
(190 4285);
DISPLAY 0.617021 (190 4285);
PAINT ORANGE (190 4285);
FORCEPROP 2 LASTPIN (200 4225) $PN 5
J 2
(190 4235);
DISPLAY 0.617021 (190 4235);
PAINT ORANGE (190 4235);
FORCEPROP 2 LASTPIN (200 4175) $PN 7
J 2
(190 4185);
DISPLAY 0.617021 (190 4185);
PAINT ORANGE (190 4185);
FORCEPROP 2 LASTPIN (200 4125) $PN 9
J 2
(190 4135);
DISPLAY 0.617021 (190 4135);
PAINT ORANGE (190 4135);
FORCEPROP 2 LASTPIN (800 4075) $PN 12
J 0
(810 4085);
DISPLAY 0.617021 (810 4085);
PAINT ORANGE (810 4085);
FORCEPROP 2 LASTPIN (200 4075) $PN 11
J 2
(190 4085);
DISPLAY 0.617021 (190 4085);
PAINT ORANGE (190 4085);
FORCEPROP 2 LASTPIN (800 4025) $PN 14
J 0
(810 4035);
DISPLAY 0.617021 (810 4035);
PAINT ORANGE (810 4035);
FORCEPROP 2 LASTPIN (800 3975) $PN 16
J 0
(810 3985);
DISPLAY 0.617021 (810 3985);
PAINT ORANGE (810 3985);
FORCEPROP 2 LASTPIN (800 3925) $PN 18
J 0
(810 3935);
DISPLAY 0.617021 (810 3935);
PAINT ORANGE (810 3935);
FORCEPROP 2 LASTPIN (800 3875) $PN 20
J 0
(810 3885);
DISPLAY 0.617021 (810 3885);
PAINT ORANGE (810 3885);
FORCEPROP 2 LASTPIN (800 3825) $PN 22
J 0
(810 3835);
DISPLAY 0.617021 (810 3835);
PAINT ORANGE (810 3835);
FORCEPROP 2 LASTPIN (800 3625) $PN 30
J 0
(810 3635);
DISPLAY 0.617021 (810 3635);
PAINT ORANGE (810 3635);
FORCEPROP 2 LASTPIN (800 3575) $PN 32
J 0
(810 3585);
DISPLAY 0.617021 (810 3585);
PAINT ORANGE (810 3585);
FORCEPROP 2 LASTPIN (800 3675) $PN 28
J 0
(810 3685);
DISPLAY 0.617021 (810 3685);
PAINT ORANGE (810 3685);
FORCEPROP 2 LASTPIN (800 3725) $PN 26
J 0
(810 3735);
DISPLAY 0.617021 (810 3735);
PAINT ORANGE (810 3735);
FORCEPROP 2 LASTPIN (800 3775) $PN 24
J 0
(810 3785);
DISPLAY 0.617021 (810 3785);
PAINT ORANGE (810 3785);
FORCEPROP 2 LASTPIN (800 3525) $PN 34
J 0
(810 3535);
DISPLAY 0.617021 (810 3535);
PAINT ORANGE (810 3535);
FORCEPROP 2 LASTPIN (800 3475) $PN 36
J 0
(810 3485);
DISPLAY 0.617021 (810 3485);
PAINT ORANGE (810 3485);
FORCEPROP 2 LASTPIN (800 3425) $PN 38
J 0
(810 3435);
DISPLAY 0.617021 (810 3435);
PAINT ORANGE (810 3435);
FORCEPROP 2 LASTPIN (800 3375) $PN 40
J 0
(810 3385);
DISPLAY 0.617021 (810 3385);
PAINT ORANGE (810 3385);
FORCEPROP 2 LASTPIN (800 3325) $PN 42
J 0
(810 3335);
DISPLAY 0.617021 (810 3335);
PAINT ORANGE (810 3335);
FORCEPROP 2 LASTPIN (800 3225) $PN 46
J 0
(810 3235);
DISPLAY 0.617021 (810 3235);
PAINT ORANGE (810 3235);
FORCEPROP 2 LASTPIN (800 3275) $PN 44
J 0
(810 3285);
DISPLAY 0.617021 (810 3285);
PAINT ORANGE (810 3285);
FORCEPROP 2 LASTPIN (800 3175) $PN 48
J 0
(810 3185);
DISPLAY 0.617021 (810 3185);
PAINT ORANGE (810 3185);
FORCEPROP 2 LASTPIN (800 3075) $PN 52
J 0
(810 3085);
DISPLAY 0.617021 (810 3085);
PAINT ORANGE (810 3085);
FORCEPROP 2 LASTPIN (800 3125) $PN 50
J 0
(810 3135);
DISPLAY 0.617021 (810 3135);
PAINT ORANGE (810 3135);
FORCEPROP 2 LASTPIN (200 3975) $PN 15
J 2
(190 3985);
DISPLAY 0.617021 (190 3985);
PAINT ORANGE (190 3985);
FORCEPROP 2 LASTPIN (200 4025) $PN 13
J 2
(190 4035);
DISPLAY 0.617021 (190 4035);
PAINT ORANGE (190 4035);
FORCEPROP 2 LASTPIN (200 3875) $PN 19
J 2
(190 3885);
DISPLAY 0.617021 (190 3885);
PAINT ORANGE (190 3885);
FORCEPROP 2 LASTPIN (200 3925) $PN 17
J 2
(190 3935);
DISPLAY 0.617021 (190 3935);
PAINT ORANGE (190 3935);
FORCEPROP 2 LASTPIN (200 3825) $PN 21
J 2
(190 3835);
DISPLAY 0.617021 (190 3835);
PAINT ORANGE (190 3835);
FORCEPROP 2 LASTPIN (200 3725) $PN 25
J 2
(190 3735);
DISPLAY 0.617021 (190 3735);
PAINT ORANGE (190 3735);
FORCEPROP 2 LASTPIN (200 3775) $PN 23
J 2
(190 3785);
DISPLAY 0.617021 (190 3785);
PAINT ORANGE (190 3785);
FORCEPROP 2 LASTPIN (200 3575) $PN 31
J 2
(190 3585);
DISPLAY 0.617021 (190 3585);
PAINT ORANGE (190 3585);
FORCEPROP 2 LASTPIN (200 3625) $PN 29
J 2
(190 3635);
DISPLAY 0.617021 (190 3635);
PAINT ORANGE (190 3635);
FORCEPROP 2 LASTPIN (200 3675) $PN 27
J 2
(190 3685);
DISPLAY 0.617021 (190 3685);
PAINT ORANGE (190 3685);
FORCEPROP 2 LASTPIN (200 3325) $PN 41
J 2
(190 3335);
DISPLAY 0.617021 (190 3335);
PAINT ORANGE (190 3335);
FORCEPROP 2 LASTPIN (200 3375) $PN 39
J 2
(190 3385);
DISPLAY 0.617021 (190 3385);
PAINT ORANGE (190 3385);
FORCEPROP 2 LASTPIN (200 3225) $PN 45
J 2
(190 3235);
DISPLAY 0.617021 (190 3235);
PAINT ORANGE (190 3235);
FORCEPROP 2 LASTPIN (200 3275) $PN 43
J 2
(190 3285);
DISPLAY 0.617021 (190 3285);
PAINT ORANGE (190 3285);
FORCEPROP 2 LASTPIN (200 3175) $PN 47
J 2
(190 3185);
DISPLAY 0.617021 (190 3185);
PAINT ORANGE (190 3185);
FORCEPROP 2 LASTPIN (200 3075) $PN 51
J 2
(190 3085);
DISPLAY 0.617021 (190 3085);
PAINT ORANGE (190 3085);
FORCEPROP 2 LASTPIN (200 3125) $PN 49
J 2
(190 3135);
DISPLAY 0.617021 (190 3135);
PAINT ORANGE (190 3135);
FORCEPROP 2 LASTPIN (800 3025) $PN 54
J 0
(810 3035);
DISPLAY 0.617021 (810 3035);
PAINT ORANGE (810 3035);
FORCEPROP 2 LASTPIN (800 2975) $PN 56
J 0
(810 2985);
DISPLAY 0.617021 (810 2985);
PAINT ORANGE (810 2985);
FORCEPROP 2 LASTPIN (800 2925) $PN 58
J 0
(810 2935);
DISPLAY 0.617021 (810 2935);
PAINT ORANGE (810 2935);
FORCEPROP 2 LASTPIN (800 2875) $PN 60
J 0
(810 2885);
DISPLAY 0.617021 (810 2885);
PAINT ORANGE (810 2885);
FORCEPROP 2 LASTPIN (800 2825) $PN 62
J 0
(810 2835);
DISPLAY 0.617021 (810 2835);
PAINT ORANGE (810 2835);
FORCEPROP 2 LASTPIN (800 2625) $PN 70
J 0
(810 2635);
DISPLAY 0.617021 (810 2635);
PAINT ORANGE (810 2635);
FORCEPROP 2 LASTPIN (800 2575) $PN 72
J 0
(810 2585);
DISPLAY 0.617021 (810 2585);
PAINT ORANGE (810 2585);
FORCEPROP 2 LASTPIN (800 2675) $PN 68
J 0
(810 2685);
DISPLAY 0.617021 (810 2685);
PAINT ORANGE (810 2685);
FORCEPROP 2 LASTPIN (800 2725) $PN 66
J 0
(810 2735);
DISPLAY 0.617021 (810 2735);
PAINT ORANGE (810 2735);
FORCEPROP 2 LASTPIN (800 2775) $PN 64
J 0
(810 2785);
DISPLAY 0.617021 (810 2785);
PAINT ORANGE (810 2785);
FORCEPROP 2 LASTPIN (800 2525) $PN 74
J 0
(810 2535);
DISPLAY 0.617021 (810 2535);
PAINT ORANGE (810 2535);
FORCEPROP 2 LASTPIN (800 2475) $PN 76
J 0
(810 2485);
DISPLAY 0.617021 (810 2485);
PAINT ORANGE (810 2485);
FORCEPROP 2 LASTPIN (800 2425) $PN 78
J 0
(810 2435);
DISPLAY 0.617021 (810 2435);
PAINT ORANGE (810 2435);
FORCEPROP 2 LASTPIN (800 2375) $PN 80
J 0
(810 2385);
DISPLAY 0.617021 (810 2385);
PAINT ORANGE (810 2385);
FORCEPROP 2 LASTPIN (800 2325) $PN 82
J 0
(810 2335);
DISPLAY 0.617021 (810 2335);
PAINT ORANGE (810 2335);
FORCEPROP 2 LASTPIN (800 2275) $PN 84
J 0
(810 2285);
DISPLAY 0.617021 (810 2285);
PAINT ORANGE (810 2285);
FORCEPROP 2 LASTPIN (800 2125) $PN 90
J 0
(810 2135);
DISPLAY 0.617021 (810 2135);
PAINT ORANGE (810 2135);
FORCEPROP 2 LASTPIN (800 2075) $PN 92
J 0
(810 2085);
DISPLAY 0.617021 (810 2085);
PAINT ORANGE (810 2085);
FORCEPROP 2 LASTPIN (800 2175) $PN 88
J 0
(810 2185);
DISPLAY 0.617021 (810 2185);
PAINT ORANGE (810 2185);
FORCEPROP 2 LASTPIN (800 2225) $PN 86
J 0
(810 2235);
DISPLAY 0.617021 (810 2235);
PAINT ORANGE (810 2235);
FORCEPROP 2 LASTPIN (200 2975) $PN 55
J 2
(190 2985);
DISPLAY 0.617021 (190 2985);
PAINT ORANGE (190 2985);
FORCEPROP 2 LASTPIN (200 3025) $PN 53
J 2
(190 3035);
DISPLAY 0.617021 (190 3035);
PAINT ORANGE (190 3035);
FORCEPROP 2 LASTPIN (200 2925) $PN 57
J 2
(190 2935);
DISPLAY 0.617021 (190 2935);
PAINT ORANGE (190 2935);
FORCEPROP 2 LASTPIN (200 2825) $PN 61
J 2
(190 2835);
DISPLAY 0.617021 (190 2835);
PAINT ORANGE (190 2835);
FORCEPROP 2 LASTPIN (200 2875) $PN 59
J 2
(190 2885);
DISPLAY 0.617021 (190 2885);
PAINT ORANGE (190 2885);
FORCEPROP 2 LASTPIN (200 2725) $PN 65
J 2
(190 2735);
DISPLAY 0.617021 (190 2735);
PAINT ORANGE (190 2735);
FORCEPROP 2 LASTPIN (200 2775) $PN 63
J 2
(190 2785);
DISPLAY 0.617021 (190 2785);
PAINT ORANGE (190 2785);
FORCEPROP 2 LASTPIN (200 2675) $PN 67
J 2
(190 2685);
DISPLAY 0.617021 (190 2685);
PAINT ORANGE (190 2685);
FORCEPROP 2 LASTPIN (200 2575) $PN 71
J 2
(190 2585);
DISPLAY 0.617021 (190 2585);
PAINT ORANGE (190 2585);
FORCEPROP 2 LASTPIN (200 2625) $PN 69
J 2
(190 2635);
DISPLAY 0.617021 (190 2635);
PAINT ORANGE (190 2635);
FORCEPROP 2 LASTPIN (200 2525) $PN 73
J 2
(190 2535);
DISPLAY 0.617021 (190 2535);
PAINT ORANGE (190 2535);
FORCEPROP 2 LASTPIN (200 2425) $PN 77
J 2
(190 2435);
DISPLAY 0.617021 (190 2435);
PAINT ORANGE (190 2435);
FORCEPROP 2 LASTPIN (200 2475) $PN 75
J 2
(190 2485);
DISPLAY 0.617021 (190 2485);
PAINT ORANGE (190 2485);
FORCEPROP 2 LASTPIN (200 2325) $PN 81
J 2
(190 2335);
DISPLAY 0.617021 (190 2335);
PAINT ORANGE (190 2335);
FORCEPROP 2 LASTPIN (200 2375) $PN 79
J 2
(190 2385);
DISPLAY 0.617021 (190 2385);
PAINT ORANGE (190 2385);
FORCEPROP 2 LASTPIN (200 2275) $PN 83
J 2
(190 2285);
DISPLAY 0.617021 (190 2285);
PAINT ORANGE (190 2285);
FORCEPROP 2 LASTPIN (200 2175) $PN 87
J 2
(190 2185);
DISPLAY 0.617021 (190 2185);
PAINT ORANGE (190 2185);
FORCEPROP 2 LASTPIN (200 2225) $PN 85
J 2
(190 2235);
DISPLAY 0.617021 (190 2235);
PAINT ORANGE (190 2235);
FORCEPROP 2 LASTPIN (200 2075) $PN 91
J 2
(190 2085);
DISPLAY 0.617021 (190 2085);
PAINT ORANGE (190 2085);
FORCEPROP 2 LASTPIN (200 2125) $PN 89
J 2
(190 2135);
DISPLAY 0.617021 (190 2135);
PAINT ORANGE (190 2135);
FORCEPROP 2 LASTPIN (800 2025) $PN 94
J 0
(810 2035);
DISPLAY 0.617021 (810 2035);
PAINT ORANGE (810 2035);
FORCEPROP 2 LASTPIN (200 2025) $PN 93
J 2
(190 2035);
DISPLAY 0.617021 (190 2035);
PAINT ORANGE (190 2035);
FORCEPROP 2 LASTPIN (800 1875) $PN 100
J 0
(810 1885);
DISPLAY 0.617021 (810 1885);
PAINT ORANGE (810 1885);
FORCEPROP 2 LASTPIN (800 1825) $PN MH2
J 0
(810 1835);
DISPLAY 0.617021 (810 1835);
PAINT ORANGE (810 1835);
FORCEPROP 2 LASTPIN (800 1925) $PN 98
J 0
(810 1935);
DISPLAY 0.617021 (810 1935);
PAINT ORANGE (810 1935);
FORCEPROP 2 LASTPIN (800 1975) $PN 96
J 0
(810 1985);
DISPLAY 0.617021 (810 1985);
PAINT ORANGE (810 1985);
FORCEPROP 1 LAST PART_NUMBER H68296-001
J 0
(250 1675);
DISPLAY 0.617021 (250 1675);
PAINT BLUE (250 1675);
FORCEPROP 2 LASTPIN (200 1975) $PN 95
J 2
(190 1985);
DISPLAY 0.617021 (190 1985);
PAINT ORANGE (190 1985);
FORCEPROP 2 LASTPIN (200 1925) $PN 97
J 2
(190 1935);
DISPLAY 0.617021 (190 1935);
PAINT ORANGE (190 1935);
FORCEPROP 2 LASTPIN (200 1875) $PN 99
J 2
(190 1885);
DISPLAY 0.617021 (190 1885);
PAINT ORANGE (190 1885);
FORCEPROP 2 LASTPIN (200 1825) $PN MH1
J 2
(190 1835);
DISPLAY 0.617021 (190 1835);
PAINT ORANGE (190 1835);
FORCEPROP 2 LAST SEC_TYPE SM
J 0
(550 4575);
DISPLAY 1.021277 (550 4575);
PAINT ORANGE (550 4575);
DISPLAY INVISIBLE (550 4575);
FORCEPROP 1 LAST PATH I258
J 0
(550 4525);
PAINT GREEN (550 4525);
DISPLAY INVISIBLE (550 4525);
FORCEPROP 2 LAST SEC 1
J 0
(550 4575);
DISPLAY 0.680851 (550 4575);
PAINT MONO (550 4575);
DISPLAY INVISIBLE (550 4575);
FORCEPROP 0 LAST ROOM IO_SLOT
J 0
(225 4675);
DISPLAY 1.021277 (225 4675);
PAINT ORANGE (225 4675);
DISPLAY INVISIBLE (225 4675);
FORCEPROP 1 LAST PACK_TYPE SM
J 0
(250 4625);
PAINT SKYBLUE (250 4625);
DISPLAY INVISIBLE (250 4625);
FORCEPROP 2 LAST CDS_LOCATION J8G1
J 0
(225 4575);
DISPLAY 0.617021 (225 4575);
PAINT AQUA (225 4575);
DISPLAY INVISIBLE (225 4575);
FORCEPROP 1 LAST CDS_LMAN_SYM_OUTLINE -250,1350,250,-1350
J 0
(500 3075);
DISPLAY 0.468085 (500 3075);
PAINT GREEN (500 3075);
DISPLAY INVISIBLE (500 3075);
FORCEPROP 2 LAST CDS_LIB mstr_sconn
J 0
(500 3075);
PAINT MONO (500 3075);
DISPLAY INVISIBLE (500 3075);
FORCEADD OFFPAGE..1
(-1525 3925);
FORCEPROP 2 LAST $XR0 108 
J 0
(-1807 3925);
DISPLAY 0.638298 (-1807 3925);
PAINT MONO (-1807 3925);
FORCEPROP 1 LAST OFFPAGE TRUE
J 0
(-1200 3800);
DISPLAY 0.872340 (-1200 3800);
PAINT GREEN (-1200 3800);
DISPLAY INVISIBLE (-1200 3800);
FORCEPROP 2 LAST PATH I259
J 0
(-1475 4000);
DISPLAY 1.021277 (-1475 4000);
PAINT ORANGE (-1475 4000);
DISPLAY INVISIBLE (-1475 4000);
FORCEPROP 2 LAST CDS_LIB mstr_standard
J 0
(-1525 3925);
PAINT MONO (-1525 3925);
DISPLAY INVISIBLE (-1525 3925);
FORCEPROP 1 LAST COMMENT_BODY TRUE
J 0
(-1400 3825);
DISPLAY 0.872340 (-1400 3825);
PAINT GREEN (-1400 3825);
DISPLAY INVISIBLE (-1400 3825);
FORCEADD OFFPAGE..3
R 2
(-1525 3975);
FORCEPROP 2 LAST $XR0 108 
J 0
(-1805 3975);
DISPLAY 0.638298 (-1805 3975);
PAINT MONO (-1805 3975);
FORCEPROP 2 LAST CDS_LIB mstr_standard
J 2
(-1525 3975);
PAINT MONO (-1525 3975);
DISPLAY INVISIBLE (-1525 3975);
FORCEPROP 1 LAST COMMENT_BODY TRUE
J 2
(-1475 3875);
DISPLAY 0.872340 (-1475 3875);
PAINT GREEN (-1475 3875);
DISPLAY INVISIBLE (-1475 3875);
FORCEPROP 2 LAST PATH I260
J 2
(-1575 4050);
DISPLAY 1.021277 (-1575 4050);
PAINT ORANGE (-1575 4050);
DISPLAY INVISIBLE (-1575 4050);
FORCEPROP 1 LAST OFFPAGE TRUE
J 2
(-1850 3850);
DISPLAY 0.872340 (-1850 3850);
PAINT GREEN (-1850 3850);
DISPLAY INVISIBLE (-1850 3850);
FORCEADD OFFPAGE..2
R 2
(-1525 3875);
FORCEPROP 2 LAST $XR1 119 
J 0
(-1900 3875);
DISPLAY 0.638298 (-1900 3875);
PAINT MONO (-1900 3875);
FORCEPROP 2 LAST $XR0 133 
J 0
(-1780 3875);
DISPLAY 0.638298 (-1780 3875);
PAINT MONO (-1780 3875);
FORCEPROP 2 LAST CDS_LIB mstr_standard
J 2
(-1525 3875);
PAINT MONO (-1525 3875);
DISPLAY INVISIBLE (-1525 3875);
FORCEPROP 1 LAST COMMENT_BODY TRUE
J 2
(-1480 3780);
DISPLAY 0.872340 (-1480 3780);
PAINT GREEN (-1480 3780);
DISPLAY INVISIBLE (-1480 3780);
FORCEPROP 2 LAST PATH I261
J 2
(-1575 3950);
DISPLAY 1.021277 (-1575 3950);
PAINT ORANGE (-1575 3950);
DISPLAY INVISIBLE (-1575 3950);
FORCEPROP 1 LAST OFFPAGE TRUE
J 2
(-1850 3750);
DISPLAY 0.872340 (-1850 3750);
PAINT GREEN (-1850 3750);
DISPLAY INVISIBLE (-1850 3750);
FORCEADD P3V3_STBY..1
(-25 4625);
FORCEPROP 3 LASTPIN (-25 4575) SIG_NAME P3V3_STBY\g
J 0
(-15 4585);
DISPLAY 0.659574 (-15 4585);
PAINT MONO (-15 4585);
DISPLAY INVISIBLE (-15 4585);
FORCEPROP 1 LAST PATH I262
J 0
(20 4627);
DISPLAY 0.340426 (20 4627);
PAINT GREEN (20 4627);
DISPLAY INVISIBLE (20 4627);
FORCEPROP 1 LAST SIZE 1B
J 0
(20 4647);
DISPLAY 0.340426 (20 4647);
PAINT GREEN (20 4647);
DISPLAY INVISIBLE (20 4647);
FORCEPROP 2 LAST CDS_LIB mstr_symbols
J 0
(-25 4625);
PAINT MONO (-25 4625);
DISPLAY INVISIBLE (-25 4625);
FORCEPROP 1 LAST VOLTAGE 3.3V
J 0
(-70 4582);
DISPLAY 0.340426 (-70 4582);
PAINT SKYBLUE (-70 4582);
DISPLAY INVISIBLE (-70 4582);
FORCEPROP 1 LAST BODY_TYPE PLUMBING
J 0
(-70 4582);
DISPLAY 0.340426 (-70 4582);
PAINT GREEN (-70 4582);
DISPLAY INVISIBLE (-70 4582);
FORCEPROP 1 LAST HDL_POWER P3V3_STBY
J 0
(-325 4500);
DISPLAY 0.872340 (-325 4500);
PAINT ORANGE (-325 4500);
DISPLAY INVISIBLE (-325 4500);
FORCEADD OFFPAGE..1
(-1525 3475);
FORCEPROP 2 LAST $XR0 114 
J 0
(-1777 3475);
DISPLAY 0.638298 (-1777 3475);
PAINT MONO (-1777 3475);
FORCEPROP 1 LAST OFFPAGE TRUE
J 0
(-1200 3350);
DISPLAY 0.872340 (-1200 3350);
PAINT GREEN (-1200 3350);
DISPLAY INVISIBLE (-1200 3350);
FORCEPROP 1 LAST COMMENT_BODY TRUE
J 0
(-1400 3375);
DISPLAY 0.872340 (-1400 3375);
PAINT GREEN (-1400 3375);
DISPLAY INVISIBLE (-1400 3375);
FORCEPROP 2 LAST CDS_LIB mstr_standard
J 0
(-1525 3475);
PAINT ORANGE (-1525 3475);
DISPLAY INVISIBLE (-1525 3475);
FORCEPROP 2 LAST PATH I264
J 0
(-1850 3525);
DISPLAY 1.021277 (-1850 3525);
PAINT ORANGE (-1850 3525);
DISPLAY INVISIBLE (-1850 3525);
FORCEADD OFFPAGE..1
(-1525 3425);
FORCEPROP 2 LAST $XR0 114 
J 0
(-1777 3425);
DISPLAY 0.638298 (-1777 3425);
PAINT MONO (-1777 3425);
FORCEPROP 2 LAST PATH I265
J 0
(-1850 3475);
DISPLAY 1.021277 (-1850 3475);
PAINT ORANGE (-1850 3475);
DISPLAY INVISIBLE (-1850 3475);
FORCEPROP 2 LAST CDS_LIB mstr_standard
J 0
(-1525 3425);
PAINT ORANGE (-1525 3425);
DISPLAY INVISIBLE (-1525 3425);
FORCEPROP 1 LAST COMMENT_BODY TRUE
J 0
(-1400 3325);
DISPLAY 0.872340 (-1400 3325);
PAINT GREEN (-1400 3325);
DISPLAY INVISIBLE (-1400 3325);
FORCEPROP 1 LAST OFFPAGE TRUE
J 0
(-1200 3300);
DISPLAY 0.872340 (-1200 3300);
PAINT GREEN (-1200 3300);
DISPLAY INVISIBLE (-1200 3300);
FORCEADD OFFPAGE..1
(-1525 3225);
FORCEPROP 2 LAST $XR0 114 
J 0
(-1777 3225);
DISPLAY 0.638298 (-1777 3225);
PAINT MONO (-1777 3225);
FORCEPROP 1 LAST OFFPAGE TRUE
J 0
(-1200 3100);
DISPLAY 0.872340 (-1200 3100);
PAINT GREEN (-1200 3100);
DISPLAY INVISIBLE (-1200 3100);
FORCEPROP 2 LAST PATH I266
J 0
(-1475 3300);
DISPLAY 1.021277 (-1475 3300);
PAINT ORANGE (-1475 3300);
DISPLAY INVISIBLE (-1475 3300);
FORCEPROP 1 LAST COMMENT_BODY TRUE
J 0
(-1400 3125);
DISPLAY 0.872340 (-1400 3125);
PAINT GREEN (-1400 3125);
DISPLAY INVISIBLE (-1400 3125);
FORCEPROP 2 LAST CDS_LIB mstr_standard
J 0
(-1525 3225);
PAINT ORANGE (-1525 3225);
DISPLAY INVISIBLE (-1525 3225);
FORCEADD OFFPAGE..1
(-1525 3175);
FORCEPROP 2 LAST $XR0 114 
J 0
(-1777 3175);
DISPLAY 0.638298 (-1777 3175);
PAINT MONO (-1777 3175);
FORCEPROP 1 LAST OFFPAGE TRUE
J 0
(-1200 3050);
DISPLAY 0.872340 (-1200 3050);
PAINT GREEN (-1200 3050);
DISPLAY INVISIBLE (-1200 3050);
FORCEPROP 2 LAST CDS_LIB mstr_standard
J 0
(-1525 3175);
PAINT ORANGE (-1525 3175);
DISPLAY INVISIBLE (-1525 3175);
FORCEPROP 2 LAST PATH I267
J 0
(-1475 3250);
DISPLAY 1.021277 (-1475 3250);
PAINT ORANGE (-1475 3250);
DISPLAY INVISIBLE (-1475 3250);
FORCEPROP 1 LAST COMMENT_BODY TRUE
J 0
(-1400 3075);
DISPLAY 0.872340 (-1400 3075);
PAINT GREEN (-1400 3075);
DISPLAY INVISIBLE (-1400 3075);
FORCEADD OFFPAGE..1
(-2625 3125);
FORCEPROP 2 LAST $XR0 244 
J 0
(-2877 3125);
DISPLAY 0.638298 (-2877 3125);
PAINT MONO (-2877 3125);
FORCEPROP 2 LAST PATH I269
J 0
(-2575 3200);
DISPLAY 1.021277 (-2575 3200);
PAINT ORANGE (-2575 3200);
DISPLAY INVISIBLE (-2575 3200);
FORCEPROP 2 LAST CDS_LIB mstr_standard
J 0
(-2625 3125);
PAINT MONO (-2625 3125);
DISPLAY INVISIBLE (-2625 3125);
FORCEPROP 1 LAST OFFPAGE TRUE
J 0
(-2300 3000);
DISPLAY 0.872340 (-2300 3000);
PAINT GREEN (-2300 3000);
DISPLAY INVISIBLE (-2300 3000);
FORCEPROP 1 LAST COMMENT_BODY TRUE
J 0
(-2500 3025);
DISPLAY 0.872340 (-2500 3025);
PAINT GREEN (-2500 3025);
DISPLAY INVISIBLE (-2500 3025);
FORCEADD OFFPAGE..1
(-2625 3075);
FORCEPROP 2 LAST $XR0 244 
J 0
(-2877 3075);
DISPLAY 0.638298 (-2877 3075);
PAINT MONO (-2877 3075);
FORCEPROP 2 LAST PATH I270
J 0
(-2575 3150);
DISPLAY 1.021277 (-2575 3150);
PAINT ORANGE (-2575 3150);
DISPLAY INVISIBLE (-2575 3150);
FORCEPROP 2 LAST CDS_LIB mstr_standard
J 0
(-2625 3075);
PAINT MONO (-2625 3075);
DISPLAY INVISIBLE (-2625 3075);
FORCEPROP 1 LAST OFFPAGE TRUE
J 0
(-2300 2950);
DISPLAY 0.872340 (-2300 2950);
PAINT GREEN (-2300 2950);
DISPLAY INVISIBLE (-2300 2950);
FORCEPROP 1 LAST COMMENT_BODY TRUE
J 0
(-2500 2975);
DISPLAY 0.872340 (-2500 2975);
PAINT GREEN (-2500 2975);
DISPLAY INVISIBLE (-2500 2975);
FORCEADD TAP..1
R 2
(-550 3075);
FORCEPROP 3 LASTPIN (-500 3075) SIG_NAME P3E_CPU0_PE1_PCH_CON_TXN<15>
J 0
(-490 3085);
DISPLAY 0.659574 (-490 3085);
PAINT MONO (-490 3085);
DISPLAY INVISIBLE (-490 3085);
FORCEPROP 1 LASTPIN (-500 3075) BN 15
J 2
(-488 3083);
DISPLAY 0.617021 (-488 3083);
PAINT GREEN (-488 3083);
FORCEPROP 1 LAST HDL_TAP TRUE
J 2
(-1050 2950);
DISPLAY 0.872340 (-1050 2950);
PAINT ORANGE (-1050 2950);
DISPLAY INVISIBLE (-1050 2950);
FORCEPROP 1 LAST PATH I271
J 2
(-548 3075);
DISPLAY 0.872340 (-548 3075);
PAINT GREEN (-548 3075);
DISPLAY INVISIBLE (-548 3075);
FORCEPROP 1 LAST BODY_TYPE PLUMBING
J 2
(-725 3125);
DISPLAY 0.872340 (-725 3125);
PAINT GREEN (-725 3125);
DISPLAY INVISIBLE (-725 3125);
FORCEPROP 2 LAST CDS_LIB mstr_standard
J 0
(-550 3075);
PAINT MONO (-550 3075);
DISPLAY INVISIBLE (-550 3075);
FORCEADD TAP..1
R 2
(-750 3025);
FORCEPROP 3 LASTPIN (-700 3025) SIG_NAME P3E_CPU0_PE1_PCH_CON_TXP<15>
J 0
(-690 3035);
DISPLAY 0.659574 (-690 3035);
PAINT MONO (-690 3035);
DISPLAY INVISIBLE (-690 3035);
FORCEPROP 1 LASTPIN (-700 3025) BN 15
J 2
(-688 3033);
DISPLAY 0.617021 (-688 3033);
PAINT GREEN (-688 3033);
FORCEPROP 1 LAST HDL_TAP TRUE
J 2
(-1250 2900);
DISPLAY 0.872340 (-1250 2900);
PAINT ORANGE (-1250 2900);
DISPLAY INVISIBLE (-1250 2900);
FORCEPROP 2 LAST CDS_LIB mstr_standard
J 0
(-750 3025);
PAINT MONO (-750 3025);
DISPLAY INVISIBLE (-750 3025);
FORCEPROP 1 LAST PATH I272
J 2
(-748 3025);
DISPLAY 0.872340 (-748 3025);
PAINT GREEN (-748 3025);
DISPLAY INVISIBLE (-748 3025);
FORCEPROP 1 LAST BODY_TYPE PLUMBING
J 2
(-925 3075);
DISPLAY 0.872340 (-925 3075);
PAINT GREEN (-925 3075);
DISPLAY INVISIBLE (-925 3075);
FORCEADD TAP..1
R 2
(-750 2925);
FORCEPROP 3 LASTPIN (-700 2925) SIG_NAME P3E_CPU0_PE1_PCH_CON_TXP<14>
J 0
(-690 2935);
DISPLAY 0.659574 (-690 2935);
PAINT MONO (-690 2935);
DISPLAY INVISIBLE (-690 2935);
FORCEPROP 1 LASTPIN (-700 2925) BN 14
J 2
(-688 2933);
DISPLAY 0.617021 (-688 2933);
PAINT GREEN (-688 2933);
FORCEPROP 2 LAST CDS_LIB mstr_standard
J 0
(-750 2925);
PAINT MONO (-750 2925);
DISPLAY INVISIBLE (-750 2925);
FORCEPROP 1 LAST PATH I273
J 2
(-748 2925);
DISPLAY 0.872340 (-748 2925);
PAINT GREEN (-748 2925);
DISPLAY INVISIBLE (-748 2925);
FORCEPROP 1 LAST BODY_TYPE PLUMBING
J 2
(-925 2975);
DISPLAY 0.872340 (-925 2975);
PAINT GREEN (-925 2975);
DISPLAY INVISIBLE (-925 2975);
FORCEPROP 1 LAST HDL_TAP TRUE
J 2
(-1250 2800);
DISPLAY 0.872340 (-1250 2800);
PAINT ORANGE (-1250 2800);
DISPLAY INVISIBLE (-1250 2800);
FORCEADD TAP..1
R 2
(-550 2875);
FORCEPROP 3 LASTPIN (-500 2875) SIG_NAME P3E_CPU0_PE1_PCH_CON_TXN<14>
J 0
(-490 2885);
DISPLAY 0.659574 (-490 2885);
PAINT MONO (-490 2885);
DISPLAY INVISIBLE (-490 2885);
FORCEPROP 1 LASTPIN (-500 2875) BN 14
J 2
(-488 2883);
DISPLAY 0.617021 (-488 2883);
PAINT GREEN (-488 2883);
FORCEPROP 1 LAST PATH I274
J 2
(-548 2875);
DISPLAY 0.872340 (-548 2875);
PAINT GREEN (-548 2875);
DISPLAY INVISIBLE (-548 2875);
FORCEPROP 2 LAST CDS_LIB mstr_standard
J 0
(-550 2875);
PAINT MONO (-550 2875);
DISPLAY INVISIBLE (-550 2875);
FORCEPROP 1 LAST BODY_TYPE PLUMBING
J 2
(-725 2925);
DISPLAY 0.872340 (-725 2925);
PAINT GREEN (-725 2925);
DISPLAY INVISIBLE (-725 2925);
FORCEPROP 1 LAST HDL_TAP TRUE
J 2
(-1050 2750);
DISPLAY 0.872340 (-1050 2750);
PAINT ORANGE (-1050 2750);
DISPLAY INVISIBLE (-1050 2750);
FORCEADD TAP..1
R 2
(-750 2625);
FORCEPROP 3 LASTPIN (-700 2625) SIG_NAME P3E_CPU0_PE1_PCH_CON_TXP<13>
J 0
(-690 2635);
DISPLAY 0.659574 (-690 2635);
PAINT MONO (-690 2635);
DISPLAY INVISIBLE (-690 2635);
FORCEPROP 1 LASTPIN (-700 2625) BN 13
J 2
(-688 2633);
DISPLAY 0.617021 (-688 2633);
PAINT GREEN (-688 2633);
FORCEPROP 1 LAST PATH I275
J 2
(-748 2625);
DISPLAY 0.872340 (-748 2625);
PAINT GREEN (-748 2625);
DISPLAY INVISIBLE (-748 2625);
FORCEPROP 2 LAST CDS_LIB mstr_standard
J 0
(-750 2625);
PAINT MONO (-750 2625);
DISPLAY INVISIBLE (-750 2625);
FORCEPROP 1 LAST BODY_TYPE PLUMBING
J 2
(-925 2675);
DISPLAY 0.872340 (-925 2675);
PAINT GREEN (-925 2675);
DISPLAY INVISIBLE (-925 2675);
FORCEPROP 1 LAST HDL_TAP TRUE
J 2
(-1250 2500);
DISPLAY 0.872340 (-1250 2500);
PAINT ORANGE (-1250 2500);
DISPLAY INVISIBLE (-1250 2500);
FORCEADD TAP..1
R 2
(-550 2675);
FORCEPROP 3 LASTPIN (-500 2675) SIG_NAME P3E_CPU0_PE1_PCH_CON_TXN<13>
J 0
(-490 2685);
DISPLAY 0.659574 (-490 2685);
PAINT MONO (-490 2685);
DISPLAY INVISIBLE (-490 2685);
FORCEPROP 1 LASTPIN (-500 2675) BN 13
J 2
(-488 2683);
DISPLAY 0.617021 (-488 2683);
PAINT GREEN (-488 2683);
FORCEPROP 1 LAST PATH I276
J 2
(-548 2675);
DISPLAY 0.872340 (-548 2675);
PAINT GREEN (-548 2675);
DISPLAY INVISIBLE (-548 2675);
FORCEPROP 2 LAST CDS_LIB mstr_standard
J 0
(-550 2675);
PAINT MONO (-550 2675);
DISPLAY INVISIBLE (-550 2675);
FORCEPROP 1 LAST BODY_TYPE PLUMBING
J 2
(-725 2725);
DISPLAY 0.872340 (-725 2725);
PAINT GREEN (-725 2725);
DISPLAY INVISIBLE (-725 2725);
FORCEPROP 1 LAST HDL_TAP TRUE
J 2
(-1050 2550);
DISPLAY 0.872340 (-1050 2550);
PAINT ORANGE (-1050 2550);
DISPLAY INVISIBLE (-1050 2550);
FORCEADD TAP..1
R 2
(-750 2475);
FORCEPROP 3 LASTPIN (-700 2475) SIG_NAME P3E_CPU0_PE1_PCH_CON_TXP<12>
J 0
(-690 2485);
DISPLAY 0.659574 (-690 2485);
PAINT MONO (-690 2485);
DISPLAY INVISIBLE (-690 2485);
FORCEPROP 1 LASTPIN (-700 2475) BN 12
J 2
(-688 2483);
DISPLAY 0.617021 (-688 2483);
PAINT GREEN (-688 2483);
FORCEPROP 1 LAST HDL_TAP TRUE
J 2
(-1250 2350);
DISPLAY 0.872340 (-1250 2350);
PAINT ORANGE (-1250 2350);
DISPLAY INVISIBLE (-1250 2350);
FORCEPROP 2 LAST CDS_LIB mstr_standard
J 0
(-750 2475);
PAINT MONO (-750 2475);
DISPLAY INVISIBLE (-750 2475);
FORCEPROP 1 LAST PATH I277
J 2
(-748 2475);
DISPLAY 0.872340 (-748 2475);
PAINT GREEN (-748 2475);
DISPLAY INVISIBLE (-748 2475);
FORCEPROP 1 LAST BODY_TYPE PLUMBING
J 2
(-925 2525);
DISPLAY 0.872340 (-925 2525);
PAINT GREEN (-925 2525);
DISPLAY INVISIBLE (-925 2525);
FORCEADD TAP..1
R 2
(-550 2525);
FORCEPROP 3 LASTPIN (-500 2525) SIG_NAME P3E_CPU0_PE1_PCH_CON_TXN<12>
J 0
(-490 2535);
DISPLAY 0.659574 (-490 2535);
PAINT MONO (-490 2535);
DISPLAY INVISIBLE (-490 2535);
FORCEPROP 1 LASTPIN (-500 2525) BN 12
J 2
(-488 2533);
DISPLAY 0.617021 (-488 2533);
PAINT GREEN (-488 2533);
FORCEPROP 1 LAST BODY_TYPE PLUMBING
J 2
(-725 2575);
DISPLAY 0.872340 (-725 2575);
PAINT GREEN (-725 2575);
DISPLAY INVISIBLE (-725 2575);
FORCEPROP 2 LAST CDS_LIB mstr_standard
J 0
(-550 2525);
PAINT MONO (-550 2525);
DISPLAY INVISIBLE (-550 2525);
FORCEPROP 1 LAST PATH I278
J 2
(-548 2525);
DISPLAY 0.872340 (-548 2525);
PAINT GREEN (-548 2525);
DISPLAY INVISIBLE (-548 2525);
FORCEPROP 1 LAST HDL_TAP TRUE
J 2
(-1050 2400);
DISPLAY 0.872340 (-1050 2400);
PAINT ORANGE (-1050 2400);
DISPLAY INVISIBLE (-1050 2400);
FORCEADD TAP..1
R 2
(-750 2325);
FORCEPROP 3 LASTPIN (-700 2325) SIG_NAME P3E_CPU0_PE1_PCH_CON_TXP<11>
J 0
(-690 2335);
DISPLAY 0.659574 (-690 2335);
PAINT MONO (-690 2335);
DISPLAY INVISIBLE (-690 2335);
FORCEPROP 1 LASTPIN (-700 2325) BN 11
J 2
(-688 2333);
DISPLAY 0.617021 (-688 2333);
PAINT GREEN (-688 2333);
FORCEPROP 1 LAST PATH I279
J 2
(-748 2325);
DISPLAY 0.872340 (-748 2325);
PAINT GREEN (-748 2325);
DISPLAY INVISIBLE (-748 2325);
FORCEPROP 2 LAST CDS_LIB mstr_standard
J 0
(-750 2325);
PAINT MONO (-750 2325);
DISPLAY INVISIBLE (-750 2325);
FORCEPROP 1 LAST BODY_TYPE PLUMBING
J 2
(-925 2375);
DISPLAY 0.872340 (-925 2375);
PAINT GREEN (-925 2375);
DISPLAY INVISIBLE (-925 2375);
FORCEPROP 1 LAST HDL_TAP TRUE
J 2
(-1250 2200);
DISPLAY 0.872340 (-1250 2200);
PAINT ORANGE (-1250 2200);
DISPLAY INVISIBLE (-1250 2200);
FORCEADD TAP..1
R 2
(-550 2375);
FORCEPROP 3 LASTPIN (-500 2375) SIG_NAME P3E_CPU0_PE1_PCH_CON_TXN<11>
J 0
(-490 2385);
DISPLAY 0.659574 (-490 2385);
PAINT MONO (-490 2385);
DISPLAY INVISIBLE (-490 2385);
FORCEPROP 1 LASTPIN (-500 2375) BN 11
J 2
(-488 2383);
DISPLAY 0.617021 (-488 2383);
PAINT GREEN (-488 2383);
FORCEPROP 1 LAST PATH I280
J 2
(-548 2375);
DISPLAY 0.872340 (-548 2375);
PAINT GREEN (-548 2375);
DISPLAY INVISIBLE (-548 2375);
FORCEPROP 2 LAST CDS_LIB mstr_standard
J 0
(-550 2375);
PAINT MONO (-550 2375);
DISPLAY INVISIBLE (-550 2375);
FORCEPROP 1 LAST BODY_TYPE PLUMBING
J 2
(-725 2425);
DISPLAY 0.872340 (-725 2425);
PAINT GREEN (-725 2425);
DISPLAY INVISIBLE (-725 2425);
FORCEPROP 1 LAST HDL_TAP TRUE
J 2
(-1050 2250);
DISPLAY 0.872340 (-1050 2250);
PAINT ORANGE (-1050 2250);
DISPLAY INVISIBLE (-1050 2250);
FORCEADD TAP..1
R 2
(-750 2175);
FORCEPROP 3 LASTPIN (-700 2175) SIG_NAME P3E_CPU0_PE1_PCH_CON_TXP<10>
J 0
(-690 2185);
DISPLAY 0.659574 (-690 2185);
PAINT MONO (-690 2185);
DISPLAY INVISIBLE (-690 2185);
FORCEPROP 1 LASTPIN (-700 2175) BN 10
J 2
(-688 2183);
DISPLAY 0.617021 (-688 2183);
PAINT GREEN (-688 2183);
FORCEPROP 2 LAST CDS_LIB mstr_standard
J 0
(-750 2175);
PAINT MONO (-750 2175);
DISPLAY INVISIBLE (-750 2175);
FORCEPROP 1 LAST PATH I281
J 2
(-748 2175);
DISPLAY 0.872340 (-748 2175);
PAINT GREEN (-748 2175);
DISPLAY INVISIBLE (-748 2175);
FORCEPROP 1 LAST BODY_TYPE PLUMBING
J 2
(-925 2225);
DISPLAY 0.872340 (-925 2225);
PAINT GREEN (-925 2225);
DISPLAY INVISIBLE (-925 2225);
FORCEPROP 1 LAST HDL_TAP TRUE
J 2
(-1250 2050);
DISPLAY 0.872340 (-1250 2050);
PAINT ORANGE (-1250 2050);
DISPLAY INVISIBLE (-1250 2050);
FORCEADD TAP..1
R 2
(-550 2225);
FORCEPROP 3 LASTPIN (-500 2225) SIG_NAME P3E_CPU0_PE1_PCH_CON_TXN<10>
J 0
(-490 2235);
DISPLAY 0.659574 (-490 2235);
PAINT MONO (-490 2235);
DISPLAY INVISIBLE (-490 2235);
FORCEPROP 1 LASTPIN (-500 2225) BN 10
J 2
(-488 2233);
DISPLAY 0.617021 (-488 2233);
PAINT GREEN (-488 2233);
FORCEPROP 1 LAST BODY_TYPE PLUMBING
J 2
(-725 2275);
DISPLAY 0.872340 (-725 2275);
PAINT GREEN (-725 2275);
DISPLAY INVISIBLE (-725 2275);
FORCEPROP 1 LAST PATH I282
J 2
(-548 2225);
DISPLAY 0.872340 (-548 2225);
PAINT GREEN (-548 2225);
DISPLAY INVISIBLE (-548 2225);
FORCEPROP 2 LAST CDS_LIB mstr_standard
J 0
(-550 2225);
PAINT MONO (-550 2225);
DISPLAY INVISIBLE (-550 2225);
FORCEPROP 1 LAST HDL_TAP TRUE
J 2
(-1050 2100);
DISPLAY 0.872340 (-1050 2100);
PAINT ORANGE (-1050 2100);
DISPLAY INVISIBLE (-1050 2100);
FORCEADD TAP..1
R 2
(-750 2025);
FORCEPROP 3 LASTPIN (-700 2025) SIG_NAME P3E_CPU0_PE1_PCH_CON_TXP<9>
J 0
(-690 2035);
DISPLAY 0.659574 (-690 2035);
PAINT MONO (-690 2035);
DISPLAY INVISIBLE (-690 2035);
FORCEPROP 1 LASTPIN (-700 2025) BN 9
J 2
(-688 2033);
DISPLAY 0.617021 (-688 2033);
PAINT GREEN (-688 2033);
FORCEPROP 1 LAST BODY_TYPE PLUMBING
J 2
(-925 2075);
DISPLAY 0.872340 (-925 2075);
PAINT GREEN (-925 2075);
DISPLAY INVISIBLE (-925 2075);
FORCEPROP 2 LAST CDS_LIB mstr_standard
J 0
(-750 2025);
PAINT MONO (-750 2025);
DISPLAY INVISIBLE (-750 2025);
FORCEPROP 1 LAST PATH I283
J 2
(-748 2025);
DISPLAY 0.872340 (-748 2025);
PAINT GREEN (-748 2025);
DISPLAY INVISIBLE (-748 2025);
FORCEPROP 1 LAST HDL_TAP TRUE
J 2
(-1250 1900);
DISPLAY 0.872340 (-1250 1900);
PAINT ORANGE (-1250 1900);
DISPLAY INVISIBLE (-1250 1900);
FORCEADD TAP..1
R 2
(-550 2075);
FORCEPROP 3 LASTPIN (-500 2075) SIG_NAME P3E_CPU0_PE1_PCH_CON_TXN<9>
J 0
(-490 2085);
DISPLAY 0.659574 (-490 2085);
PAINT MONO (-490 2085);
DISPLAY INVISIBLE (-490 2085);
FORCEPROP 1 LASTPIN (-500 2075) BN 9
J 2
(-488 2083);
DISPLAY 0.617021 (-488 2083);
PAINT GREEN (-488 2083);
FORCEPROP 1 LAST PATH I284
J 2
(-548 2075);
DISPLAY 0.872340 (-548 2075);
PAINT GREEN (-548 2075);
DISPLAY INVISIBLE (-548 2075);
FORCEPROP 2 LAST CDS_LIB mstr_standard
J 0
(-550 2075);
PAINT MONO (-550 2075);
DISPLAY INVISIBLE (-550 2075);
FORCEPROP 1 LAST BODY_TYPE PLUMBING
J 2
(-725 2125);
DISPLAY 0.872340 (-725 2125);
PAINT GREEN (-725 2125);
DISPLAY INVISIBLE (-725 2125);
FORCEPROP 1 LAST HDL_TAP TRUE
J 2
(-1050 1950);
DISPLAY 0.872340 (-1050 1950);
PAINT ORANGE (-1050 1950);
DISPLAY INVISIBLE (-1050 1950);
FORCEADD TAP..1
R 2
(-750 1875);
FORCEPROP 3 LASTPIN (-700 1875) SIG_NAME P3E_CPU0_PE1_PCH_CON_TXP<8>
J 0
(-690 1885);
DISPLAY 0.659574 (-690 1885);
PAINT MONO (-690 1885);
DISPLAY INVISIBLE (-690 1885);
FORCEPROP 1 LASTPIN (-700 1875) BN 8
J 2
(-688 1883);
DISPLAY 0.617021 (-688 1883);
PAINT GREEN (-688 1883);
FORCEPROP 2 LAST CDS_LIB mstr_standard
J 0
(-750 1875);
PAINT MONO (-750 1875);
DISPLAY INVISIBLE (-750 1875);
FORCEPROP 1 LAST PATH I285
J 2
(-748 1875);
DISPLAY 0.872340 (-748 1875);
PAINT GREEN (-748 1875);
DISPLAY INVISIBLE (-748 1875);
FORCEPROP 1 LAST BODY_TYPE PLUMBING
J 2
(-925 1925);
DISPLAY 0.872340 (-925 1925);
PAINT GREEN (-925 1925);
DISPLAY INVISIBLE (-925 1925);
FORCEPROP 1 LAST HDL_TAP TRUE
J 2
(-1250 1750);
DISPLAY 0.872340 (-1250 1750);
PAINT ORANGE (-1250 1750);
DISPLAY INVISIBLE (-1250 1750);
FORCEADD TAP..1
R 2
(-550 1925);
FORCEPROP 3 LASTPIN (-500 1925) SIG_NAME P3E_CPU0_PE1_PCH_CON_TXN<8>
J 0
(-490 1935);
DISPLAY 0.659574 (-490 1935);
PAINT MONO (-490 1935);
DISPLAY INVISIBLE (-490 1935);
FORCEPROP 1 LASTPIN (-500 1925) BN 8
J 2
(-488 1933);
DISPLAY 0.617021 (-488 1933);
PAINT GREEN (-488 1933);
FORCEPROP 2 LAST CDS_LIB mstr_standard
J 0
(-550 1925);
PAINT MONO (-550 1925);
DISPLAY INVISIBLE (-550 1925);
FORCEPROP 1 LAST PATH I286
J 2
(-548 1925);
DISPLAY 0.872340 (-548 1925);
PAINT GREEN (-548 1925);
DISPLAY INVISIBLE (-548 1925);
FORCEPROP 1 LAST BODY_TYPE PLUMBING
J 2
(-725 1975);
DISPLAY 0.872340 (-725 1975);
PAINT GREEN (-725 1975);
DISPLAY INVISIBLE (-725 1975);
FORCEPROP 1 LAST HDL_TAP TRUE
J 2
(-1050 1800);
DISPLAY 0.872340 (-1050 1800);
PAINT ORANGE (-1050 1800);
DISPLAY INVISIBLE (-1050 1800);
FORCEADD OFFPAGE..4
(2300 3475);
FORCEPROP 2 LAST $XR0 114 
J 0
(2486 3475);
DISPLAY 0.638298 (2486 3475);
PAINT MONO (2486 3475);
FORCEPROP 1 LAST COMMENT_BODY TRUE
J 0
(2275 3375);
DISPLAY 0.638298 (2275 3375);
PAINT GREEN (2275 3375);
DISPLAY INVISIBLE (2275 3375);
FORCEPROP 2 LAST CDS_LIB mstr_standard
J 0
(2300 3475);
PAINT MONO (2300 3475);
DISPLAY INVISIBLE (2300 3475);
FORCEPROP 2 LAST PATH I287
J 0
(2475 3550);
DISPLAY 1.021277 (2475 3550);
PAINT ORANGE (2475 3550);
DISPLAY INVISIBLE (2475 3550);
FORCEPROP 1 LAST OFFPAGE TRUE
J 0
(2625 3350);
PAINT GREEN (2625 3350);
DISPLAY INVISIBLE (2625 3350);
FORCEADD OFFPAGE..4
(2300 3425);
FORCEPROP 2 LAST $XR0 114 
J 0
(2486 3425);
DISPLAY 0.638298 (2486 3425);
PAINT MONO (2486 3425);
FORCEPROP 1 LAST OFFPAGE TRUE
J 0
(2625 3300);
PAINT GREEN (2625 3300);
DISPLAY INVISIBLE (2625 3300);
FORCEPROP 2 LAST PATH I288
J 0
(2475 3500);
DISPLAY 1.021277 (2475 3500);
PAINT ORANGE (2475 3500);
DISPLAY INVISIBLE (2475 3500);
FORCEPROP 2 LAST CDS_LIB mstr_standard
J 0
(2300 3425);
PAINT MONO (2300 3425);
DISPLAY INVISIBLE (2300 3425);
FORCEPROP 1 LAST COMMENT_BODY TRUE
J 0
(2275 3325);
DISPLAY 0.638298 (2275 3325);
PAINT GREEN (2275 3325);
DISPLAY INVISIBLE (2275 3325);
FORCEADD OFFPAGE..4
(2300 3325);
FORCEPROP 2 LAST $XR0 114 
J 0
(2486 3325);
DISPLAY 0.638298 (2486 3325);
PAINT MONO (2486 3325);
FORCEPROP 1 LAST OFFPAGE TRUE
J 0
(2625 3200);
PAINT GREEN (2625 3200);
DISPLAY INVISIBLE (2625 3200);
FORCEPROP 2 LAST PATH I289
J 0
(2475 3400);
DISPLAY 1.021277 (2475 3400);
PAINT ORANGE (2475 3400);
DISPLAY INVISIBLE (2475 3400);
FORCEPROP 2 LAST CDS_LIB mstr_standard
J 0
(2300 3325);
PAINT MONO (2300 3325);
DISPLAY INVISIBLE (2300 3325);
FORCEPROP 1 LAST COMMENT_BODY TRUE
J 0
(2275 3225);
DISPLAY 0.638298 (2275 3225);
PAINT GREEN (2275 3225);
DISPLAY INVISIBLE (2275 3225);
FORCEADD OFFPAGE..4
(2300 3275);
FORCEPROP 2 LAST $XR0 114 
J 0
(2486 3275);
DISPLAY 0.638298 (2486 3275);
PAINT MONO (2486 3275);
FORCEPROP 1 LAST OFFPAGE TRUE
J 0
(2625 3150);
PAINT GREEN (2625 3150);
DISPLAY INVISIBLE (2625 3150);
FORCEPROP 2 LAST PATH I290
J 0
(2475 3350);
DISPLAY 1.021277 (2475 3350);
PAINT ORANGE (2475 3350);
DISPLAY INVISIBLE (2475 3350);
FORCEPROP 2 LAST CDS_LIB mstr_standard
J 0
(2300 3275);
PAINT MONO (2300 3275);
DISPLAY INVISIBLE (2300 3275);
FORCEPROP 1 LAST COMMENT_BODY TRUE
J 0
(2275 3175);
DISPLAY 0.638298 (2275 3175);
PAINT GREEN (2275 3175);
DISPLAY INVISIBLE (2275 3175);
FORCEADD OFFPAGE..4
(2300 3125);
FORCEPROP 2 LAST $XR0 114 
J 0
(2486 3125);
DISPLAY 0.638298 (2486 3125);
PAINT MONO (2486 3125);
FORCEPROP 2 LAST PATH I291
J 0
(2475 3200);
DISPLAY 1.021277 (2475 3200);
PAINT ORANGE (2475 3200);
DISPLAY INVISIBLE (2475 3200);
FORCEPROP 2 LAST CDS_LIB mstr_standard
J 0
(2300 3125);
PAINT MONO (2300 3125);
DISPLAY INVISIBLE (2300 3125);
FORCEPROP 1 LAST OFFPAGE TRUE
J 0
(2625 3000);
PAINT GREEN (2625 3000);
DISPLAY INVISIBLE (2625 3000);
FORCEPROP 1 LAST COMMENT_BODY TRUE
J 0
(2275 3025);
DISPLAY 0.638298 (2275 3025);
PAINT GREEN (2275 3025);
DISPLAY INVISIBLE (2275 3025);
FORCEADD OFFPAGE..4
(2300 3175);
FORCEPROP 2 LAST $XR0 114 
J 0
(2486 3175);
DISPLAY 0.638298 (2486 3175);
PAINT MONO (2486 3175);
FORCEPROP 2 LAST PATH I292
J 0
(2475 3250);
DISPLAY 1.021277 (2475 3250);
PAINT ORANGE (2475 3250);
DISPLAY INVISIBLE (2475 3250);
FORCEPROP 2 LAST CDS_LIB mstr_standard
J 0
(2300 3175);
PAINT MONO (2300 3175);
DISPLAY INVISIBLE (2300 3175);
FORCEPROP 1 LAST COMMENT_BODY TRUE
J 0
(2275 3075);
DISPLAY 0.638298 (2275 3075);
PAINT GREEN (2275 3075);
DISPLAY INVISIBLE (2275 3075);
FORCEPROP 1 LAST OFFPAGE TRUE
J 0
(2625 3050);
PAINT GREEN (2625 3050);
DISPLAY INVISIBLE (2625 3050);
FORCEADD OFFPAGE..2
(2850 3075);
FORCEPROP 2 LAST $XR0 109 
J 0
(3039 3075);
DISPLAY 0.638298 (3039 3075);
PAINT MONO (3039 3075);
FORCEPROP 2 LAST $XR1 244 
J 0
(3039 3075);
DISPLAY 0.638298 (3039 3075);
PAINT MONO (3039 3075);
FORCEPROP 2 LAST PATH I293
J 0
(3025 3150);
DISPLAY 1.021277 (3025 3150);
PAINT ORANGE (3025 3150);
DISPLAY INVISIBLE (3025 3150);
FORCEPROP 2 LAST CDS_LIB mstr_standard
J 0
(2850 3075);
PAINT MONO (2850 3075);
DISPLAY INVISIBLE (2850 3075);
FORCEPROP 1 LAST OFFPAGE TRUE
J 0
(3175 2950);
DISPLAY 0.872340 (3175 2950);
PAINT GREEN (3175 2950);
DISPLAY INVISIBLE (3175 2950);
FORCEPROP 1 LAST COMMENT_BODY TRUE
J 0
(2805 2980);
DISPLAY 0.872340 (2805 2980);
PAINT GREEN (2805 2980);
DISPLAY INVISIBLE (2805 2980);
FORCEADD OFFPAGE..2
(2825 2975);
FORCEPROP 2 LAST $XR1 ?
J 0
(3134 2975);
DISPLAY 0.638298 (3134 2975);
PAINT MONO (3134 2975);
FORCEPROP 2 LAST $XR0 244 
J 0
(3014 2975);
DISPLAY 0.638298 (3014 2975);
PAINT MONO (3014 2975);
FORCEPROP 1 LAST COMMENT_BODY TRUE
J 0
(2780 2880);
DISPLAY 0.872340 (2780 2880);
PAINT GREEN (2780 2880);
DISPLAY INVISIBLE (2780 2880);
FORCEPROP 2 LAST CDS_LIB mstr_standard
J 0
(2825 2975);
PAINT MONO (2825 2975);
DISPLAY INVISIBLE (2825 2975);
FORCEPROP 1 LAST OFFPAGE TRUE
J 0
(3150 2850);
DISPLAY 0.872340 (3150 2850);
PAINT GREEN (3150 2850);
DISPLAY INVISIBLE (3150 2850);
FORCEPROP 2 LAST PATH I294
J 0
(3000 3050);
DISPLAY 1.021277 (3000 3050);
PAINT ORANGE (3000 3050);
DISPLAY INVISIBLE (3000 3050);
FORCEADD TAP..1
(1350 2975);
FORCEPROP 3 LASTPIN (1300 2975) SIG_NAME P3E_CPU0_PE1_PCH_CON_RXP<15>
J 0
(1310 2985);
DISPLAY 0.659574 (1310 2985);
PAINT MONO (1310 2985);
DISPLAY INVISIBLE (1310 2985);
FORCEPROP 1 LASTPIN (1300 2975) BN 15
J 0
(1288 2983);
DISPLAY 0.617021 (1288 2983);
PAINT PINK (1288 2983);
FORCEPROP 1 LAST BODY_TYPE PLUMBING
J 0
(1350 3025);
DISPLAY 0.638298 (1350 3025);
PAINT GREEN (1350 3025);
DISPLAY INVISIBLE (1350 3025);
FORCEPROP 1 LAST HDL_TAP TRUE
J 0
(1675 2850);
DISPLAY 0.638298 (1675 2850);
PAINT GREEN (1675 2850);
DISPLAY INVISIBLE (1675 2850);
FORCEPROP 2 LAST CDS_LIB mstr_standard
J 0
(1350 2975);
PAINT MONO (1350 2975);
DISPLAY INVISIBLE (1350 2975);
FORCEPROP 1 LAST PATH I295
J 0
(1348 2975);
DISPLAY 0.872340 (1348 2975);
PAINT GREEN (1348 2975);
DISPLAY INVISIBLE (1348 2975);
FORCEADD TAP..1
(1500 3025);
FORCEPROP 3 LASTPIN (1450 3025) SIG_NAME P3E_CPU0_PE1_PCH_CON_RXN<15>
J 0
(1460 3035);
DISPLAY 0.659574 (1460 3035);
PAINT MONO (1460 3035);
DISPLAY INVISIBLE (1460 3035);
FORCEPROP 1 LASTPIN (1450 3025) BN 15
J 0
(1438 3033);
DISPLAY 0.617021 (1438 3033);
PAINT PINK (1438 3033);
FORCEPROP 1 LAST HDL_TAP TRUE
J 0
(1825 2900);
DISPLAY 0.638298 (1825 2900);
PAINT GREEN (1825 2900);
DISPLAY INVISIBLE (1825 2900);
FORCEPROP 1 LAST PATH I296
J 0
(1498 3025);
DISPLAY 0.872340 (1498 3025);
PAINT GREEN (1498 3025);
DISPLAY INVISIBLE (1498 3025);
FORCEPROP 1 LAST BODY_TYPE PLUMBING
J 0
(1500 3075);
DISPLAY 0.638298 (1500 3075);
PAINT GREEN (1500 3075);
DISPLAY INVISIBLE (1500 3075);
FORCEPROP 2 LAST CDS_LIB mstr_standard
J 0
(1500 3025);
PAINT MONO (1500 3025);
DISPLAY INVISIBLE (1500 3025);
FORCEADD TAP..1
(1500 2875);
FORCEPROP 3 LASTPIN (1450 2875) SIG_NAME P3E_CPU0_PE1_PCH_CON_RXN<14>
J 0
(1460 2885);
DISPLAY 0.659574 (1460 2885);
PAINT MONO (1460 2885);
DISPLAY INVISIBLE (1460 2885);
FORCEPROP 1 LASTPIN (1450 2875) BN 14
J 0
(1438 2883);
DISPLAY 0.617021 (1438 2883);
PAINT GREEN (1438 2883);
FORCEPROP 2 LAST CDS_LIB mstr_standard
J 0
(1500 2875);
PAINT MONO (1500 2875);
DISPLAY INVISIBLE (1500 2875);
FORCEPROP 1 LAST BODY_TYPE PLUMBING
J 0
(1500 2925);
DISPLAY 0.638298 (1500 2925);
PAINT GREEN (1500 2925);
DISPLAY INVISIBLE (1500 2925);
FORCEPROP 1 LAST PATH I297
J 0
(1498 2875);
DISPLAY 0.872340 (1498 2875);
PAINT GREEN (1498 2875);
DISPLAY INVISIBLE (1498 2875);
FORCEPROP 1 LAST HDL_TAP TRUE
J 0
(1825 2750);
DISPLAY 0.638298 (1825 2750);
PAINT GREEN (1825 2750);
DISPLAY INVISIBLE (1825 2750);
FORCEADD TAP..1
(1350 2825);
FORCEPROP 3 LASTPIN (1300 2825) SIG_NAME P3E_CPU0_PE1_PCH_CON_RXP<14>
J 0
(1310 2835);
DISPLAY 0.659574 (1310 2835);
PAINT MONO (1310 2835);
DISPLAY INVISIBLE (1310 2835);
FORCEPROP 1 LASTPIN (1300 2825) BN 14
J 0
(1288 2833);
DISPLAY 0.617021 (1288 2833);
PAINT GREEN (1288 2833);
FORCEPROP 1 LAST HDL_TAP TRUE
J 0
(1675 2700);
DISPLAY 0.638298 (1675 2700);
PAINT GREEN (1675 2700);
DISPLAY INVISIBLE (1675 2700);
FORCEPROP 1 LAST BODY_TYPE PLUMBING
J 0
(1350 2875);
DISPLAY 0.638298 (1350 2875);
PAINT GREEN (1350 2875);
DISPLAY INVISIBLE (1350 2875);
FORCEPROP 1 LAST PATH I298
J 0
(1348 2825);
DISPLAY 0.872340 (1348 2825);
PAINT GREEN (1348 2825);
DISPLAY INVISIBLE (1348 2825);
FORCEPROP 2 LAST CDS_LIB mstr_standard
J 0
(1350 2825);
PAINT MONO (1350 2825);
DISPLAY INVISIBLE (1350 2825);
FORCEADD TAP..1
(1500 2625);
FORCEPROP 3 LASTPIN (1450 2625) SIG_NAME P3E_CPU0_PE1_PCH_CON_RXN<13>
J 0
(1460 2635);
DISPLAY 0.659574 (1460 2635);
PAINT MONO (1460 2635);
DISPLAY INVISIBLE (1460 2635);
FORCEPROP 1 LASTPIN (1450 2625) BN 13
J 0
(1438 2633);
DISPLAY 0.617021 (1438 2633);
PAINT GREEN (1438 2633);
FORCEPROP 1 LAST HDL_TAP TRUE
J 0
(1825 2500);
DISPLAY 0.638298 (1825 2500);
PAINT GREEN (1825 2500);
DISPLAY INVISIBLE (1825 2500);
FORCEPROP 1 LAST PATH I299
J 0
(1498 2625);
DISPLAY 0.872340 (1498 2625);
PAINT GREEN (1498 2625);
DISPLAY INVISIBLE (1498 2625);
FORCEPROP 1 LAST BODY_TYPE PLUMBING
J 0
(1500 2675);
DISPLAY 0.638298 (1500 2675);
PAINT GREEN (1500 2675);
DISPLAY INVISIBLE (1500 2675);
FORCEPROP 2 LAST CDS_LIB mstr_standard
J 0
(1500 2625);
PAINT MONO (1500 2625);
DISPLAY INVISIBLE (1500 2625);
FORCEADD TAP..1
(1350 2575);
FORCEPROP 3 LASTPIN (1300 2575) SIG_NAME P3E_CPU0_PE1_PCH_CON_RXP<13>
J 0
(1310 2585);
DISPLAY 0.659574 (1310 2585);
PAINT MONO (1310 2585);
DISPLAY INVISIBLE (1310 2585);
FORCEPROP 1 LASTPIN (1300 2575) BN 13
J 0
(1288 2583);
DISPLAY 0.617021 (1288 2583);
PAINT GREEN (1288 2583);
FORCEPROP 1 LAST HDL_TAP TRUE
J 0
(1675 2450);
DISPLAY 0.638298 (1675 2450);
PAINT GREEN (1675 2450);
DISPLAY INVISIBLE (1675 2450);
FORCEPROP 1 LAST PATH I300
J 0
(1348 2575);
DISPLAY 0.872340 (1348 2575);
PAINT GREEN (1348 2575);
DISPLAY INVISIBLE (1348 2575);
FORCEPROP 1 LAST BODY_TYPE PLUMBING
J 0
(1350 2625);
DISPLAY 0.638298 (1350 2625);
PAINT GREEN (1350 2625);
DISPLAY INVISIBLE (1350 2625);
FORCEPROP 2 LAST CDS_LIB mstr_standard
J 0
(1350 2575);
PAINT MONO (1350 2575);
DISPLAY INVISIBLE (1350 2575);
FORCEADD TAP..1
(1500 2475);
FORCEPROP 3 LASTPIN (1450 2475) SIG_NAME P3E_CPU0_PE1_PCH_CON_RXN<12>
J 0
(1460 2485);
DISPLAY 0.659574 (1460 2485);
PAINT MONO (1460 2485);
DISPLAY INVISIBLE (1460 2485);
FORCEPROP 1 LASTPIN (1450 2475) BN 12
J 0
(1438 2483);
DISPLAY 0.617021 (1438 2483);
PAINT GREEN (1438 2483);
FORCEPROP 1 LAST HDL_TAP TRUE
J 0
(1825 2350);
DISPLAY 0.638298 (1825 2350);
PAINT GREEN (1825 2350);
DISPLAY INVISIBLE (1825 2350);
FORCEPROP 2 LAST CDS_LIB mstr_standard
J 0
(1500 2475);
PAINT MONO (1500 2475);
DISPLAY INVISIBLE (1500 2475);
FORCEPROP 1 LAST BODY_TYPE PLUMBING
J 0
(1500 2525);
DISPLAY 0.638298 (1500 2525);
PAINT GREEN (1500 2525);
DISPLAY INVISIBLE (1500 2525);
FORCEPROP 1 LAST PATH I301
J 0
(1498 2475);
DISPLAY 0.872340 (1498 2475);
PAINT GREEN (1498 2475);
DISPLAY INVISIBLE (1498 2475);
FORCEADD TAP..1
(1350 2425);
FORCEPROP 3 LASTPIN (1300 2425) SIG_NAME P3E_CPU0_PE1_PCH_CON_RXP<12>
J 0
(1310 2435);
DISPLAY 0.659574 (1310 2435);
PAINT MONO (1310 2435);
DISPLAY INVISIBLE (1310 2435);
FORCEPROP 1 LASTPIN (1300 2425) BN 12
J 0
(1288 2433);
DISPLAY 0.617021 (1288 2433);
PAINT GREEN (1288 2433);
FORCEPROP 1 LAST PATH I302
J 0
(1348 2425);
DISPLAY 0.872340 (1348 2425);
PAINT GREEN (1348 2425);
DISPLAY INVISIBLE (1348 2425);
FORCEPROP 1 LAST BODY_TYPE PLUMBING
J 0
(1350 2475);
DISPLAY 0.638298 (1350 2475);
PAINT GREEN (1350 2475);
DISPLAY INVISIBLE (1350 2475);
FORCEPROP 2 LAST CDS_LIB mstr_standard
J 0
(1350 2425);
PAINT MONO (1350 2425);
DISPLAY INVISIBLE (1350 2425);
FORCEPROP 1 LAST HDL_TAP TRUE
J 0
(1675 2300);
DISPLAY 0.638298 (1675 2300);
PAINT GREEN (1675 2300);
DISPLAY INVISIBLE (1675 2300);
FORCEADD TAP..1
(1500 2325);
FORCEPROP 3 LASTPIN (1450 2325) SIG_NAME P3E_CPU0_PE1_PCH_CON_RXN<11>
J 0
(1460 2335);
DISPLAY 0.659574 (1460 2335);
PAINT MONO (1460 2335);
DISPLAY INVISIBLE (1460 2335);
FORCEPROP 1 LASTPIN (1450 2325) BN 11
J 0
(1438 2333);
DISPLAY 0.617021 (1438 2333);
PAINT GREEN (1438 2333);
FORCEPROP 1 LAST HDL_TAP TRUE
J 0
(1825 2200);
DISPLAY 0.638298 (1825 2200);
PAINT GREEN (1825 2200);
DISPLAY INVISIBLE (1825 2200);
FORCEPROP 1 LAST BODY_TYPE PLUMBING
J 0
(1500 2375);
DISPLAY 0.638298 (1500 2375);
PAINT GREEN (1500 2375);
DISPLAY INVISIBLE (1500 2375);
FORCEPROP 2 LAST CDS_LIB mstr_standard
J 0
(1500 2325);
PAINT MONO (1500 2325);
DISPLAY INVISIBLE (1500 2325);
FORCEPROP 1 LAST PATH I303
J 0
(1498 2325);
DISPLAY 0.872340 (1498 2325);
PAINT GREEN (1498 2325);
DISPLAY INVISIBLE (1498 2325);
FORCEADD TAP..1
(1350 2275);
FORCEPROP 3 LASTPIN (1300 2275) SIG_NAME P3E_CPU0_PE1_PCH_CON_RXP<11>
J 0
(1310 2285);
DISPLAY 0.659574 (1310 2285);
PAINT MONO (1310 2285);
DISPLAY INVISIBLE (1310 2285);
FORCEPROP 1 LASTPIN (1300 2275) BN 11
J 0
(1288 2283);
DISPLAY 0.617021 (1288 2283);
PAINT GREEN (1288 2283);
FORCEPROP 1 LAST HDL_TAP TRUE
J 0
(1675 2150);
DISPLAY 0.638298 (1675 2150);
PAINT GREEN (1675 2150);
DISPLAY INVISIBLE (1675 2150);
FORCEPROP 2 LAST CDS_LIB mstr_standard
J 0
(1350 2275);
PAINT MONO (1350 2275);
DISPLAY INVISIBLE (1350 2275);
FORCEPROP 1 LAST BODY_TYPE PLUMBING
J 0
(1350 2325);
DISPLAY 0.638298 (1350 2325);
PAINT GREEN (1350 2325);
DISPLAY INVISIBLE (1350 2325);
FORCEPROP 1 LAST PATH I304
J 0
(1348 2275);
DISPLAY 0.872340 (1348 2275);
PAINT GREEN (1348 2275);
DISPLAY INVISIBLE (1348 2275);
FORCEADD TAP..1
(1500 2175);
FORCEPROP 3 LASTPIN (1450 2175) SIG_NAME P3E_CPU0_PE1_PCH_CON_RXN<10>
J 0
(1460 2185);
DISPLAY 0.659574 (1460 2185);
PAINT MONO (1460 2185);
DISPLAY INVISIBLE (1460 2185);
FORCEPROP 1 LASTPIN (1450 2175) BN 10
J 0
(1438 2183);
DISPLAY 0.617021 (1438 2183);
PAINT GREEN (1438 2183);
FORCEPROP 1 LAST HDL_TAP TRUE
J 0
(1825 2050);
DISPLAY 0.638298 (1825 2050);
PAINT GREEN (1825 2050);
DISPLAY INVISIBLE (1825 2050);
FORCEPROP 1 LAST PATH I305
J 0
(1498 2175);
DISPLAY 0.872340 (1498 2175);
PAINT GREEN (1498 2175);
DISPLAY INVISIBLE (1498 2175);
FORCEPROP 1 LAST BODY_TYPE PLUMBING
J 0
(1500 2225);
DISPLAY 0.638298 (1500 2225);
PAINT GREEN (1500 2225);
DISPLAY INVISIBLE (1500 2225);
FORCEPROP 2 LAST CDS_LIB mstr_standard
J 0
(1500 2175);
PAINT MONO (1500 2175);
DISPLAY INVISIBLE (1500 2175);
FORCEADD TAP..1
(1350 2125);
FORCEPROP 3 LASTPIN (1300 2125) SIG_NAME P3E_CPU0_PE1_PCH_CON_RXP<10>
J 0
(1310 2135);
DISPLAY 0.659574 (1310 2135);
PAINT MONO (1310 2135);
DISPLAY INVISIBLE (1310 2135);
FORCEPROP 1 LASTPIN (1300 2125) BN 10
J 0
(1288 2133);
DISPLAY 0.617021 (1288 2133);
PAINT GREEN (1288 2133);
FORCEPROP 1 LAST HDL_TAP TRUE
J 0
(1675 2000);
DISPLAY 0.638298 (1675 2000);
PAINT GREEN (1675 2000);
DISPLAY INVISIBLE (1675 2000);
FORCEPROP 1 LAST BODY_TYPE PLUMBING
J 0
(1350 2175);
DISPLAY 0.638298 (1350 2175);
PAINT GREEN (1350 2175);
DISPLAY INVISIBLE (1350 2175);
FORCEPROP 1 LAST PATH I306
J 0
(1348 2125);
DISPLAY 0.872340 (1348 2125);
PAINT GREEN (1348 2125);
DISPLAY INVISIBLE (1348 2125);
FORCEPROP 2 LAST CDS_LIB mstr_standard
J 0
(1350 2125);
PAINT MONO (1350 2125);
DISPLAY INVISIBLE (1350 2125);
FORCEADD TAP..1
(1500 1975);
FORCEPROP 3 LASTPIN (1450 1975) SIG_NAME P3E_CPU0_PE1_PCH_CON_RXN<9>
J 0
(1460 1985);
DISPLAY 0.659574 (1460 1985);
PAINT MONO (1460 1985);
DISPLAY INVISIBLE (1460 1985);
FORCEPROP 1 LASTPIN (1450 1975) BN 9
J 0
(1438 1983);
DISPLAY 0.617021 (1438 1983);
PAINT GREEN (1438 1983);
FORCEPROP 1 LAST PATH I307
J 0
(1498 1975);
DISPLAY 0.872340 (1498 1975);
PAINT GREEN (1498 1975);
DISPLAY INVISIBLE (1498 1975);
FORCEPROP 2 LAST CDS_LIB mstr_standard
J 0
(1500 1975);
PAINT MONO (1500 1975);
DISPLAY INVISIBLE (1500 1975);
FORCEPROP 1 LAST HDL_TAP TRUE
J 0
(1825 1850);
DISPLAY 0.638298 (1825 1850);
PAINT GREEN (1825 1850);
DISPLAY INVISIBLE (1825 1850);
FORCEPROP 1 LAST BODY_TYPE PLUMBING
J 0
(1500 2025);
DISPLAY 0.638298 (1500 2025);
PAINT GREEN (1500 2025);
DISPLAY INVISIBLE (1500 2025);
FORCEADD TAP..1
(1350 2025);
FORCEPROP 3 LASTPIN (1300 2025) SIG_NAME P3E_CPU0_PE1_PCH_CON_RXP<9>
J 0
(1310 2035);
DISPLAY 0.659574 (1310 2035);
PAINT MONO (1310 2035);
DISPLAY INVISIBLE (1310 2035);
FORCEPROP 1 LASTPIN (1300 2025) BN 9
J 0
(1288 2033);
DISPLAY 0.617021 (1288 2033);
PAINT GREEN (1288 2033);
FORCEPROP 1 LAST HDL_TAP TRUE
J 0
(1675 1900);
DISPLAY 0.638298 (1675 1900);
PAINT GREEN (1675 1900);
DISPLAY INVISIBLE (1675 1900);
FORCEPROP 1 LAST PATH I308
J 0
(1348 2025);
DISPLAY 0.872340 (1348 2025);
PAINT GREEN (1348 2025);
DISPLAY INVISIBLE (1348 2025);
FORCEPROP 2 LAST CDS_LIB mstr_standard
J 0
(1350 2025);
PAINT MONO (1350 2025);
DISPLAY INVISIBLE (1350 2025);
FORCEPROP 1 LAST BODY_TYPE PLUMBING
J 0
(1350 2075);
DISPLAY 0.638298 (1350 2075);
PAINT GREEN (1350 2075);
DISPLAY INVISIBLE (1350 2075);
FORCEADD OFFPAGE..2
(2850 3925);
FORCEPROP 2 LAST $XR1 119 
J 0
(3159 3925);
DISPLAY 0.638298 (3159 3925);
PAINT MONO (3159 3925);
FORCEPROP 2 LAST $XR0 133 
J 0
(3039 3925);
DISPLAY 0.638298 (3039 3925);
PAINT MONO (3039 3925);
FORCEPROP 1 LAST OFFPAGE TRUE
J 0
(3175 3800);
DISPLAY 0.872340 (3175 3800);
PAINT GREEN (3175 3800);
DISPLAY INVISIBLE (3175 3800);
FORCEPROP 2 LAST PATH I310
J 0
(3025 4000);
DISPLAY 1.021277 (3025 4000);
PAINT ORANGE (3025 4000);
DISPLAY INVISIBLE (3025 4000);
FORCEPROP 2 LAST CDS_LIB mstr_standard
J 0
(2850 3925);
PAINT MONO (2850 3925);
DISPLAY INVISIBLE (2850 3925);
FORCEPROP 1 LAST COMMENT_BODY TRUE
J 0
(2805 3830);
DISPLAY 0.872340 (2805 3830);
PAINT GREEN (2805 3830);
DISPLAY INVISIBLE (2805 3830);
FORCEADD OFFPAGE..2
(2325 3675);
FORCEPROP 2 LAST $XR0 142 
J 0
(2514 3675);
DISPLAY 0.638298 (2514 3675);
PAINT MONO (2514 3675);
FORCEPROP 1 LAST OFFPAGE TRUE
J 0
(2650 3550);
DISPLAY 0.872340 (2650 3550);
PAINT GREEN (2650 3550);
DISPLAY INVISIBLE (2650 3550);
FORCEPROP 2 LAST PATH I314
J 0
(2500 3750);
DISPLAY 1.021277 (2500 3750);
PAINT ORANGE (2500 3750);
DISPLAY INVISIBLE (2500 3750);
FORCEPROP 2 LAST CDS_LIB mstr_standard
J 0
(2325 3675);
PAINT MONO (2325 3675);
DISPLAY INVISIBLE (2325 3675);
FORCEPROP 1 LAST COMMENT_BODY TRUE
J 0
(2280 3580);
DISPLAY 0.872340 (2280 3580);
PAINT GREEN (2280 3580);
DISPLAY INVISIBLE (2280 3580);
FORCEADD CAP_A..1
(-1950 1350);
FORCEPROP 1 LAST LOCATION C2U23
J 0
(-1900 1450);
DISPLAY 0.617021 (-1900 1450);
PAINT AQUA (-1900 1450);
FORCEPROP 1 LAST PACK_TYPE 0402V
J 0
(-1900 1150);
DISPLAY 0.617021 (-1900 1150);
PAINT SKYBLUE (-1900 1150);
FORCEPROP 1 LAST VALUE 0.1UF
J 0
(-1900 1400);
DISPLAY 0.617021 (-1900 1400);
PAINT SKYBLUE (-1900 1400);
FORCEPROP 1 LAST PART_NUMBER A36096-030
J 0
(-1900 1200);
DISPLAY 0.617021 (-1900 1200);
PAINT BLUE (-1900 1200);
FORCEPROP 1 LAST VOLTAGE 16V
J 0
(-1900 1350);
DISPLAY 0.617021 (-1900 1350);
PAINT SKYBLUE (-1900 1350);
FORCEPROP 1 LASTPIN (-1950 1450) $PN 1
J 0
(-1940 1430);
DISPLAY 0.617021 (-1940 1430);
PAINT ORANGE (-1940 1430);
FORCEPROP 1 LAST TOLERANCE 10%
J 0
(-1900 1300);
DISPLAY 0.617021 (-1900 1300);
PAINT SKYBLUE (-1900 1300);
FORCEPROP 1 LAST MATERIAL X7R
J 0
(-1900 1250);
DISPLAY 0.617021 (-1900 1250);
PAINT SKYBLUE (-1900 1250);
FORCEPROP 1 LASTPIN (-1950 1250) $PN 2
J 0
(-1940 1230);
DISPLAY 0.617021 (-1940 1230);
PAINT ORANGE (-1940 1230);
FORCEPROP 0 LAST ROOM IO_SLOT
J 0
(-1900 1550);
DISPLAY 1.021277 (-1900 1550);
PAINT ORANGE (-1900 1550);
DISPLAY INVISIBLE (-1900 1550);
FORCEPROP 2 LAST SEC_TYPE 0402V
J 0
(-1900 1550);
DISPLAY 1.021277 (-1900 1550);
PAINT ORANGE (-1900 1550);
DISPLAY INVISIBLE (-1900 1550);
FORCEPROP 2 LAST SEC 1
J 0
(-1900 1550);
PAINT MONO (-1900 1550);
DISPLAY INVISIBLE (-1900 1550);
FORCEPROP 1 LAST PATH I315
J 0
(-1900 1500);
DISPLAY 0.978723 (-1900 1500);
PAINT WHITE (-1900 1500);
DISPLAY INVISIBLE (-1900 1500);
FORCEPROP 2 LAST CDS_SEC 1
J 0
(-1900 1500);
PAINT ORANGE (-1900 1500);
DISPLAY INVISIBLE (-1900 1500);
FORCEPROP 2 LAST CDS_LOCATION C2U23
J 0
(-1900 1450);
DISPLAY 0.617021 (-1900 1450);
PAINT AQUA (-1900 1450);
DISPLAY INVISIBLE (-1900 1450);
FORCEPROP 2 LAST CDS_LIB dev_discrete
J 0
(-1950 1350);
PAINT ORANGE (-1950 1350);
DISPLAY INVISIBLE (-1950 1350);
FORCEADD GND..1
(-1950 950);
FORCEPROP 3 LASTPIN (-1950 1000) SIG_NAME GND\g
J 0
(-1940 1010);
DISPLAY 0.659574 (-1940 1010);
PAINT MONO (-1940 1010);
DISPLAY INVISIBLE (-1940 1010);
FORCEPROP 1 LAST HDL_POWER GND
J 0
(-1950 1100);
DISPLAY 0.872340 (-1950 1100);
PAINT GREEN (-1950 1100);
DISPLAY INVISIBLE (-1950 1100);
FORCEPROP 1 LAST VOLTAGE 0
J 0
(-1950 950);
PAINT SKYBLUE (-1950 950);
DISPLAY INVISIBLE (-1950 950);
FORCEPROP 1 LAST SIZE 1B
J 0
(-1875 900);
DISPLAY 0.872340 (-1875 900);
PAINT AQUA (-1875 900);
DISPLAY INVISIBLE (-1875 900);
FORCEPROP 2 LAST CDS_LIB mstr_symbols
J 0
(-1950 950);
PAINT MONO (-1950 950);
DISPLAY INVISIBLE (-1950 950);
FORCEPROP 1 LAST BODY_TYPE PLUMBING
J 0
(-1995 907);
DISPLAY 0.340426 (-1995 907);
PAINT GREEN (-1995 907);
DISPLAY INVISIBLE (-1995 907);
FORCEPROP 1 LAST PATH I316
J 0
(-1875 950);
DISPLAY 0.872340 (-1875 950);
PAINT AQUA (-1875 950);
DISPLAY INVISIBLE (-1875 950);
FORCEADD CAP_A..1
(-2350 1375);
FORCEPROP 1 LAST PACK_TYPE 0402V
J 0
(-2300 1175);
DISPLAY 0.617021 (-2300 1175);
PAINT SKYBLUE (-2300 1175);
FORCEPROP 1 LAST VOLTAGE 16V
J 0
(-2300 1375);
DISPLAY 0.617021 (-2300 1375);
PAINT SKYBLUE (-2300 1375);
FORCEPROP 1 LAST TOLERANCE 10%
J 0
(-2300 1325);
DISPLAY 0.617021 (-2300 1325);
PAINT SKYBLUE (-2300 1325);
FORCEPROP 1 LAST PART_NUMBER A36096-030
J 0
(-2300 1225);
DISPLAY 0.617021 (-2300 1225);
PAINT BLUE (-2300 1225);
FORCEPROP 1 LAST MATERIAL X7R
J 0
(-2300 1275);
DISPLAY 0.617021 (-2300 1275);
PAINT SKYBLUE (-2300 1275);
FORCEPROP 1 LAST VALUE 0.1UF
J 0
(-2300 1425);
DISPLAY 0.617021 (-2300 1425);
PAINT SKYBLUE (-2300 1425);
FORCEPROP 1 LAST LOCATION C2U22
J 0
(-2300 1475);
DISPLAY 0.617021 (-2300 1475);
PAINT AQUA (-2300 1475);
FORCEPROP 1 LASTPIN (-2350 1475) $PN 1
J 0
(-2340 1455);
DISPLAY 0.617021 (-2340 1455);
PAINT ORANGE (-2340 1455);
FORCEPROP 1 LASTPIN (-2350 1275) $PN 2
J 0
(-2340 1255);
DISPLAY 0.617021 (-2340 1255);
PAINT ORANGE (-2340 1255);
FORCEPROP 2 LAST SEC 1
J 0
(-2300 1575);
PAINT MONO (-2300 1575);
DISPLAY INVISIBLE (-2300 1575);
FORCEPROP 2 LAST SEC_TYPE 0402V
J 0
(-2300 1575);
DISPLAY 1.021277 (-2300 1575);
PAINT ORANGE (-2300 1575);
DISPLAY INVISIBLE (-2300 1575);
FORCEPROP 0 LAST ROOM IO_SLOT
J 0
(-2300 1575);
DISPLAY 1.021277 (-2300 1575);
PAINT ORANGE (-2300 1575);
DISPLAY INVISIBLE (-2300 1575);
FORCEPROP 1 LAST PATH I318
J 0
(-2300 1525);
DISPLAY 0.978723 (-2300 1525);
PAINT WHITE (-2300 1525);
DISPLAY INVISIBLE (-2300 1525);
FORCEPROP 2 LAST CDS_SEC 1
J 0
(-2300 1525);
PAINT ORANGE (-2300 1525);
DISPLAY INVISIBLE (-2300 1525);
FORCEPROP 2 LAST CDS_LOCATION C2U22
J 0
(-2300 1475);
DISPLAY 0.617021 (-2300 1475);
PAINT AQUA (-2300 1475);
DISPLAY INVISIBLE (-2300 1475);
FORCEPROP 2 LAST CDS_LIB dev_discrete
J 0
(-2350 1375);
PAINT ORANGE (-2350 1375);
DISPLAY INVISIBLE (-2350 1375);
FORCEADD P3V3_STBY..1
(-2350 1625);
FORCEPROP 3 LASTPIN (-2350 1575) SIG_NAME P3V3_STBY\g
J 0
(-2340 1585);
DISPLAY 0.659574 (-2340 1585);
PAINT MONO (-2340 1585);
DISPLAY INVISIBLE (-2340 1585);
FORCEPROP 2 LAST CDS_LIB mstr_symbols
J 0
(-2350 1625);
PAINT MONO (-2350 1625);
DISPLAY INVISIBLE (-2350 1625);
FORCEPROP 1 LAST PATH I319
J 0
(-2305 1627);
DISPLAY 0.340426 (-2305 1627);
PAINT GREEN (-2305 1627);
DISPLAY INVISIBLE (-2305 1627);
FORCEPROP 1 LAST SIZE 1B
J 0
(-2305 1647);
DISPLAY 0.340426 (-2305 1647);
PAINT GREEN (-2305 1647);
DISPLAY INVISIBLE (-2305 1647);
FORCEPROP 1 LAST BODY_TYPE PLUMBING
J 0
(-2395 1582);
DISPLAY 0.340426 (-2395 1582);
PAINT GREEN (-2395 1582);
DISPLAY INVISIBLE (-2395 1582);
FORCEPROP 1 LAST VOLTAGE 3.3V
J 0
(-2395 1582);
DISPLAY 0.340426 (-2395 1582);
PAINT SKYBLUE (-2395 1582);
DISPLAY INVISIBLE (-2395 1582);
FORCEPROP 1 LAST HDL_POWER P3V3_STBY
J 0
(-2650 1500);
DISPLAY 0.872340 (-2650 1500);
PAINT ORANGE (-2650 1500);
DISPLAY INVISIBLE (-2650 1500);
FORCEADD RES..1
(-2400 4600);
FORCEPROP 1 LAST MATERIAL EMPTY
J 0
(-2125 4550);
DISPLAY 0.617021 (-2125 4550);
PAINT RED (-2125 4550);
FORCEPROP 1 LAST PART_NUMBER G21796-173
J 0
(-2100 4600);
DISPLAY 0.617021 (-2100 4600);
PAINT BLUE (-2100 4600);
FORCEPROP 1 LASTPIN (-2300 4600) $PN 2
J 0
(-2338 4612);
DISPLAY 0.617021 (-2338 4612);
PAINT ORANGE (-2338 4612);
FORCEPROP 1 LASTPIN (-2500 4600) $PN 1
J 0
(-2488 4612);
DISPLAY 0.617021 (-2488 4612);
PAINT ORANGE (-2488 4612);
FORCEPROP 1 LAST TOLERANCE 1%
J 0
(-2250 4550);
DISPLAY 0.617021 (-2250 4550);
PAINT SKYBLUE (-2250 4550);
FORCEPROP 1 LAST VALUE 20.0
J 2
(-2500 4550);
DISPLAY 0.617021 (-2500 4550);
PAINT SKYBLUE (-2500 4550);
FORCEPROP 1 LAST LOCATION R2U35
J 0
(-2750 4550);
DISPLAY 0.617021 (-2750 4550);
PAINT AQUA (-2750 4550);
FORCEPROP 0 LAST BOM_COST SM_CONTROLLER
J 0
(-2150 4750);
DISPLAY 1.021277 (-2150 4750);
PAINT ORANGE (-2150 4750);
DISPLAY INVISIBLE (-2150 4750);
FORCEPROP 0 LAST SKU A
J 0
(-2150 4650);
DISPLAY 1.021277 (-2150 4650);
PAINT ORANGE (-2150 4650);
DISPLAY INVISIBLE (-2150 4650);
FORCEPROP 0 LAST ROOM SMBUS
J 0
(-2150 4650);
DISPLAY 1.021277 (-2150 4650);
PAINT ORANGE (-2150 4650);
DISPLAY INVISIBLE (-2150 4650);
FORCEPROP 2 LAST CDS_SEC 1
J 0
(-2450 4800);
PAINT MONO (-2450 4800);
DISPLAY INVISIBLE (-2450 4800);
FORCEPROP 2 LAST $SEC 1
J 0
(-2450 4800);
PAINT MONO (-2450 4800);
DISPLAY INVISIBLE (-2450 4800);
FORCEPROP 1 LAST PATH I320
J 0
(-2450 4750);
DISPLAY 0.978723 (-2450 4750);
PAINT WHITE (-2450 4750);
DISPLAY INVISIBLE (-2450 4750);
FORCEPROP 2 LAST CDS_LIB mstr_discrete
J 0
(-2400 4600);
PAINT MONO (-2400 4600);
DISPLAY INVISIBLE (-2400 4600);
FORCEPROP 1 LAST PACK_TYPE 0402
J 0
(-2250 4550);
DISPLAY 0.617021 (-2250 4550);
PAINT SKYBLUE (-2250 4550);
DISPLAY INVISIBLE (-2250 4550);
FORCEPROP 1 LAST WATTAGE 1/16W
J 2
(-2525 4550);
DISPLAY 0.617021 (-2525 4550);
PAINT SKYBLUE (-2525 4550);
DISPLAY INVISIBLE (-2525 4550);
FORCEPROP 2 LAST CDS_LOCATION R2U35
J 0
(-2650 4550);
DISPLAY 0.617021 (-2650 4550);
PAINT AQUA (-2650 4550);
DISPLAY INVISIBLE (-2650 4550);
FORCEADD OFFPAGE..6
(-3175 4600);
FORCEPROP 2 LAST $XR2 190 
J 0
(-3545 4636);
DISPLAY 0.638298 (-3545 4636);
PAINT MONO (-3545 4636);
FORCEPROP 2 LAST $XR0 138 
J 0
(-3545 4600);
DISPLAY 0.638298 (-3545 4600);
PAINT MONO (-3545 4600);
FORCEPROP 2 LAST $XR1 183 
J 0
(-3545 4564);
DISPLAY 0.638298 (-3545 4564);
PAINT MONO (-3545 4564);
FORCEPROP 1 LAST OFFPAGE TRUE
J 0
(-2850 4475);
DISPLAY 0.872340 (-2850 4475);
PAINT GREEN (-2850 4475);
DISPLAY INVISIBLE (-2850 4475);
FORCEPROP 2 LAST PATH I322
J 0
(-3125 4675);
DISPLAY 1.021277 (-3125 4675);
PAINT ORANGE (-3125 4675);
DISPLAY INVISIBLE (-3125 4675);
FORCEPROP 2 LAST CDS_LIB mstr_standard
J 0
(-3175 4600);
PAINT MONO (-3175 4600);
DISPLAY INVISIBLE (-3175 4600);
FORCEPROP 1 LAST COMMENT_BODY TRUE
J 0
(-3075 4525);
DISPLAY 0.872340 (-3075 4525);
PAINT GREEN (-3075 4525);
DISPLAY INVISIBLE (-3075 4525);
FORCEADD OFFPAGE..6
(-3175 4500);
FORCEPROP 2 LAST $XR1 163 
J 0
(-3545 4464);
DISPLAY 0.638298 (-3545 4464);
PAINT MONO (-3545 4464);
FORCEPROP 2 LAST $XR0 160 
J 0
(-3545 4500);
DISPLAY 0.638298 (-3545 4500);
PAINT MONO (-3545 4500);
FORCEPROP 1 LAST OFFPAGE TRUE
J 0
(-2850 4375);
DISPLAY 0.872340 (-2850 4375);
PAINT GREEN (-2850 4375);
DISPLAY INVISIBLE (-2850 4375);
FORCEPROP 2 LAST PATH I323
J 0
(-3125 4575);
DISPLAY 1.021277 (-3125 4575);
PAINT ORANGE (-3125 4575);
DISPLAY INVISIBLE (-3125 4575);
FORCEPROP 2 LAST CDS_LIB mstr_standard
J 0
(-3175 4500);
PAINT MONO (-3175 4500);
DISPLAY INVISIBLE (-3175 4500);
FORCEPROP 1 LAST COMMENT_BODY TRUE
J 0
(-3075 4425);
DISPLAY 0.872340 (-3075 4425);
PAINT GREEN (-3075 4425);
DISPLAY INVISIBLE (-3075 4425);
FORCEADD OFFPAGE..3
(-1200 4500);
FORCEPROP 2 LAST $XR0 108 
J 0
(-986 4500);
DISPLAY 0.638298 (-986 4500);
PAINT MONO (-986 4500);
FORCEPROP 1 LAST OFFPAGE TRUE
J 0
(-875 4375);
DISPLAY 0.872340 (-875 4375);
PAINT GREEN (-875 4375);
DISPLAY INVISIBLE (-875 4375);
FORCEPROP 2 LAST PATH I324
J 0
(-1150 4575);
DISPLAY 1.021277 (-1150 4575);
PAINT ORANGE (-1150 4575);
DISPLAY INVISIBLE (-1150 4575);
FORCEPROP 1 LAST COMMENT_BODY TRUE
J 0
(-1250 4400);
DISPLAY 0.872340 (-1250 4400);
PAINT GREEN (-1250 4400);
DISPLAY INVISIBLE (-1250 4400);
FORCEPROP 2 LAST CDS_LIB mstr_standard
J 0
(-1200 4500);
PAINT MONO (-1200 4500);
DISPLAY INVISIBLE (-1200 4500);
FORCEADD OFFPAGE..2
(-1200 4250);
FORCEPROP 2 LAST $XR0 108 
J 0
(-1011 4250);
DISPLAY 0.638298 (-1011 4250);
PAINT MONO (-1011 4250);
FORCEPROP 1 LAST OFFPAGE TRUE
J 0
(-875 4125);
DISPLAY 0.872340 (-875 4125);
PAINT GREEN (-875 4125);
DISPLAY INVISIBLE (-875 4125);
FORCEPROP 2 LAST PATH I325
J 0
(-1000 4325);
DISPLAY 1.021277 (-1000 4325);
PAINT ORANGE (-1000 4325);
DISPLAY INVISIBLE (-1000 4325);
FORCEPROP 2 LAST CDS_LIB mstr_standard
J 0
(-1200 4250);
PAINT MONO (-1200 4250);
DISPLAY INVISIBLE (-1200 4250);
FORCEPROP 1 LAST COMMENT_BODY TRUE
J 0
(-1245 4155);
DISPLAY 0.872340 (-1245 4155);
PAINT GREEN (-1245 4155);
DISPLAY INVISIBLE (-1245 4155);
FORCEADD OFFPAGE..1
(-3175 4350);
FORCEPROP 2 LAST $XR2 190 
J 0
(-3547 4386);
DISPLAY 0.638298 (-3547 4386);
PAINT MONO (-3547 4386);
FORCEPROP 2 LAST $XR1 183 
J 0
(-3547 4314);
DISPLAY 0.638298 (-3547 4314);
PAINT MONO (-3547 4314);
FORCEPROP 2 LAST $XR0 138 
J 0
(-3547 4350);
DISPLAY 0.638298 (-3547 4350);
PAINT MONO (-3547 4350);
FORCEPROP 1 LAST OFFPAGE TRUE
J 0
(-2850 4225);
DISPLAY 0.872340 (-2850 4225);
PAINT GREEN (-2850 4225);
DISPLAY INVISIBLE (-2850 4225);
FORCEPROP 1 LAST COMMENT_BODY TRUE
J 0
(-3050 4250);
DISPLAY 0.872340 (-3050 4250);
PAINT GREEN (-3050 4250);
DISPLAY INVISIBLE (-3050 4250);
FORCEPROP 2 LAST PATH I328
J 0
(-3125 4425);
DISPLAY 1.021277 (-3125 4425);
PAINT ORANGE (-3125 4425);
DISPLAY INVISIBLE (-3125 4425);
FORCEPROP 2 LAST CDS_LIB mstr_standard
J 0
(-3175 4350);
PAINT MONO (-3175 4350);
DISPLAY INVISIBLE (-3175 4350);
FORCEADD OFFPAGE..1
(-3175 4250);
FORCEPROP 2 LAST $XR1 163 
J 0
(-3547 4214);
DISPLAY 0.638298 (-3547 4214);
PAINT MONO (-3547 4214);
FORCEPROP 2 LAST $XR0 160 
J 0
(-3547 4250);
DISPLAY 0.638298 (-3547 4250);
PAINT MONO (-3547 4250);
FORCEPROP 1 LAST OFFPAGE TRUE
J 0
(-2850 4125);
DISPLAY 0.872340 (-2850 4125);
PAINT GREEN (-2850 4125);
DISPLAY INVISIBLE (-2850 4125);
FORCEPROP 1 LAST COMMENT_BODY TRUE
J 0
(-3050 4150);
DISPLAY 0.872340 (-3050 4150);
PAINT GREEN (-3050 4150);
DISPLAY INVISIBLE (-3050 4150);
FORCEPROP 2 LAST PATH I329
J 0
(-3125 4325);
DISPLAY 1.021277 (-3125 4325);
PAINT ORANGE (-3125 4325);
DISPLAY INVISIBLE (-3125 4325);
FORCEPROP 2 LAST CDS_LIB mstr_standard
J 0
(-3175 4250);
PAINT MONO (-3175 4250);
DISPLAY INVISIBLE (-3175 4250);
FORCEADD RES..1
(-2400 4500);
FORCEPROP 1 LAST PART_NUMBER G21796-173
J 0
(-2100 4450);
DISPLAY 0.617021 (-2100 4450);
PAINT BLUE (-2100 4450);
FORCEPROP 1 LAST MATERIAL CHIP
J 0
(-2250 4450);
DISPLAY 0.617021 (-2250 4450);
PAINT SKYBLUE (-2250 4450);
FORCEPROP 1 LAST TOLERANCE 1%
J 0
(-2325 4450);
DISPLAY 0.617021 (-2325 4450);
PAINT SKYBLUE (-2325 4450);
FORCEPROP 1 LASTPIN (-2300 4500) $PN 2
J 0
(-2338 4512);
DISPLAY 0.617021 (-2338 4512);
PAINT ORANGE (-2338 4512);
FORCEPROP 1 LASTPIN (-2500 4500) $PN 1
J 0
(-2488 4512);
DISPLAY 0.617021 (-2488 4512);
PAINT ORANGE (-2488 4512);
FORCEPROP 1 LAST VALUE 20.0
J 2
(-2500 4450);
DISPLAY 0.617021 (-2500 4450);
PAINT SKYBLUE (-2500 4450);
FORCEPROP 1 LAST LOCATION R2U31
J 0
(-2750 4450);
DISPLAY 0.617021 (-2750 4450);
PAINT AQUA (-2750 4450);
FORCEPROP 0 LAST BOM_COST SM_CONTROLLER
J 0
(-2150 4650);
DISPLAY 1.021277 (-2150 4650);
PAINT ORANGE (-2150 4650);
DISPLAY INVISIBLE (-2150 4650);
FORCEPROP 2 LAST CDS_SEC 1
J 0
(-2450 4700);
PAINT MONO (-2450 4700);
DISPLAY INVISIBLE (-2450 4700);
FORCEPROP 2 LAST $SEC 1
J 0
(-2450 4700);
PAINT MONO (-2450 4700);
DISPLAY INVISIBLE (-2450 4700);
FORCEPROP 1 LAST PATH I330
J 0
(-2450 4650);
DISPLAY 0.978723 (-2450 4650);
PAINT WHITE (-2450 4650);
DISPLAY INVISIBLE (-2450 4650);
FORCEPROP 0 LAST ROOM SMBUS
J 0
(-2150 4550);
DISPLAY 1.021277 (-2150 4550);
PAINT ORANGE (-2150 4550);
DISPLAY INVISIBLE (-2150 4550);
FORCEPROP 0 LAST SKU B
J 0
(-2150 4550);
DISPLAY 1.021277 (-2150 4550);
PAINT ORANGE (-2150 4550);
DISPLAY INVISIBLE (-2150 4550);
FORCEPROP 1 LAST PACK_TYPE 0402
J 0
(-2250 4450);
DISPLAY 0.617021 (-2250 4450);
PAINT SKYBLUE (-2250 4450);
DISPLAY INVISIBLE (-2250 4450);
FORCEPROP 2 LAST CDS_LIB mstr_discrete
J 0
(-2400 4500);
PAINT MONO (-2400 4500);
DISPLAY INVISIBLE (-2400 4500);
FORCEPROP 1 LAST WATTAGE 1/16W
J 2
(-2525 4450);
DISPLAY 0.617021 (-2525 4450);
PAINT SKYBLUE (-2525 4450);
DISPLAY INVISIBLE (-2525 4450);
FORCEPROP 2 LAST CDS_LOCATION R2U31
J 0
(-2650 4450);
DISPLAY 0.617021 (-2650 4450);
PAINT AQUA (-2650 4450);
DISPLAY INVISIBLE (-2650 4450);
FORCEADD OFFPAGE..2
(2850 3875);
FORCEPROP 2 LAST $XR0 119 
J 0
(3039 3875);
DISPLAY 0.638298 (3039 3875);
PAINT MONO (3039 3875);
FORCEPROP 1 LAST OFFPAGE TRUE
J 0
(3175 3750);
DISPLAY 0.872340 (3175 3750);
PAINT GREEN (3175 3750);
DISPLAY INVISIBLE (3175 3750);
FORCEPROP 2 LAST PATH I333
J 0
(3025 3950);
DISPLAY 1.021277 (3025 3950);
PAINT ORANGE (3025 3950);
DISPLAY INVISIBLE (3025 3950);
FORCEPROP 2 LAST CDS_LIB mstr_standard
J 0
(2850 3875);
PAINT MONO (2850 3875);
DISPLAY INVISIBLE (2850 3875);
FORCEPROP 1 LAST COMMENT_BODY TRUE
J 0
(2805 3780);
DISPLAY 0.872340 (2805 3780);
PAINT GREEN (2805 3780);
DISPLAY INVISIBLE (2805 3780);
FORCEADD OFFPAGE..2
(2300 2725);
FORCEPROP 2 LAST $XR0 133 
J 0
(2489 2725);
DISPLAY 0.638298 (2489 2725);
PAINT MONO (2489 2725);
FORCEPROP 2 LAST $XR1 121 
J 0
(2609 2725);
DISPLAY 0.638298 (2609 2725);
PAINT MONO (2609 2725);
FORCEPROP 1 LAST OFFPAGE TRUE
J 0
(2625 2600);
DISPLAY 0.872340 (2625 2600);
PAINT GREEN (2625 2600);
DISPLAY INVISIBLE (2625 2600);
FORCEPROP 2 LAST PATH I334
J 0
(2475 2800);
DISPLAY 1.021277 (2475 2800);
PAINT ORANGE (2475 2800);
DISPLAY INVISIBLE (2475 2800);
FORCEPROP 1 LAST COMMENT_BODY TRUE
J 0
(2255 2630);
DISPLAY 0.872340 (2255 2630);
PAINT GREEN (2255 2630);
DISPLAY INVISIBLE (2255 2630);
FORCEPROP 2 LAST CDS_LIB mstr_standard
J 0
(2300 2725);
PAINT MONO (2300 2725);
DISPLAY INVISIBLE (2300 2725);
FORCEADD OFFPAGE..2
(2325 3575);
FORCEPROP 2 LAST $XR1 121 
J 0
(2634 3575);
DISPLAY 0.638298 (2634 3575);
PAINT MONO (2634 3575);
FORCEPROP 2 LAST $XR0 133 
J 0
(2514 3575);
DISPLAY 0.638298 (2514 3575);
PAINT MONO (2514 3575);
FORCEPROP 1 LAST OFFPAGE TRUE
J 0
(2650 3450);
DISPLAY 0.872340 (2650 3450);
PAINT GREEN (2650 3450);
DISPLAY INVISIBLE (2650 3450);
FORCEPROP 2 LAST PATH I335
J 0
(2500 3650);
DISPLAY 1.021277 (2500 3650);
PAINT ORANGE (2500 3650);
DISPLAY INVISIBLE (2500 3650);
FORCEPROP 2 LAST CDS_LIB mstr_standard
J 0
(2325 3575);
PAINT MONO (2325 3575);
DISPLAY INVISIBLE (2325 3575);
FORCEPROP 1 LAST COMMENT_BODY TRUE
J 0
(2280 3480);
DISPLAY 0.872340 (2280 3480);
PAINT GREEN (2280 3480);
DISPLAY INVISIBLE (2280 3480);
FORCEADD OFFPAGE..2
(2325 3625);
FORCEPROP 2 LAST $XR1 121 
J 0
(2634 3625);
DISPLAY 0.638298 (2634 3625);
PAINT MONO (2634 3625);
FORCEPROP 2 LAST $XR0 133 
J 0
(2514 3625);
DISPLAY 0.638298 (2514 3625);
PAINT MONO (2514 3625);
FORCEPROP 1 LAST OFFPAGE TRUE
J 0
(2650 3500);
DISPLAY 0.872340 (2650 3500);
PAINT GREEN (2650 3500);
DISPLAY INVISIBLE (2650 3500);
FORCEPROP 2 LAST PATH I336
J 0
(2500 3700);
DISPLAY 1.021277 (2500 3700);
PAINT ORANGE (2500 3700);
DISPLAY INVISIBLE (2500 3700);
FORCEPROP 2 LAST CDS_LIB mstr_standard
J 0
(2325 3625);
PAINT MONO (2325 3625);
DISPLAY INVISIBLE (2325 3625);
FORCEPROP 1 LAST COMMENT_BODY TRUE
J 0
(2280 3530);
DISPLAY 0.872340 (2280 3530);
PAINT GREEN (2280 3530);
DISPLAY INVISIBLE (2280 3530);
FORCEADD OFFPAGE..2
R 2
(-1550 2775);
FORCEPROP 2 LAST $XR1 121 
J 0
(-1925 2775);
DISPLAY 0.638298 (-1925 2775);
PAINT MONO (-1925 2775);
FORCEPROP 2 LAST $XR0 133 
J 0
(-1805 2775);
DISPLAY 0.638298 (-1805 2775);
PAINT MONO (-1805 2775);
FORCEPROP 2 LAST PATH I337
J 0
(-1500 2850);
DISPLAY 1.021277 (-1500 2850);
PAINT ORANGE (-1500 2850);
DISPLAY INVISIBLE (-1500 2850);
FORCEPROP 1 LAST COMMENT_BODY TRUE
J 2
(-1505 2680);
DISPLAY 0.872340 (-1505 2680);
PAINT GREEN (-1505 2680);
DISPLAY INVISIBLE (-1505 2680);
FORCEPROP 2 LAST CDS_LIB mstr_standard
J 0
(-1550 2775);
PAINT MONO (-1550 2775);
DISPLAY INVISIBLE (-1550 2775);
FORCEPROP 1 LAST OFFPAGE TRUE
J 2
(-1875 2650);
DISPLAY 0.872340 (-1875 2650);
PAINT GREEN (-1875 2650);
DISPLAY INVISIBLE (-1875 2650);
FORCEADD OFFPAGE..2
R 2
(-1550 3675);
FORCEPROP 2 LAST $XR1 121 
J 0
(-1925 3675);
DISPLAY 0.638298 (-1925 3675);
PAINT MONO (-1925 3675);
FORCEPROP 2 LAST $XR0 133 
J 0
(-1805 3675);
DISPLAY 0.638298 (-1805 3675);
PAINT MONO (-1805 3675);
FORCEPROP 2 LAST PATH I338
J 0
(-1500 3750);
DISPLAY 1.021277 (-1500 3750);
PAINT ORANGE (-1500 3750);
DISPLAY INVISIBLE (-1500 3750);
FORCEPROP 1 LAST COMMENT_BODY TRUE
J 2
(-1505 3580);
DISPLAY 0.872340 (-1505 3580);
PAINT GREEN (-1505 3580);
DISPLAY INVISIBLE (-1505 3580);
FORCEPROP 2 LAST CDS_LIB mstr_standard
J 0
(-1550 3675);
PAINT MONO (-1550 3675);
DISPLAY INVISIBLE (-1550 3675);
FORCEPROP 1 LAST OFFPAGE TRUE
J 2
(-1875 3550);
DISPLAY 0.872340 (-1875 3550);
PAINT GREEN (-1875 3550);
DISPLAY INVISIBLE (-1875 3550);
FORCEADD RES..1
(-2400 4250);
FORCEPROP 1 LAST PART_NUMBER G21796-173
J 0
(-2100 4200);
DISPLAY 0.617021 (-2100 4200);
PAINT BLUE (-2100 4200);
FORCEPROP 1 LAST MATERIAL CHIP
J 0
(-2250 4200);
DISPLAY 0.617021 (-2250 4200);
PAINT SKYBLUE (-2250 4200);
FORCEPROP 1 LAST TOLERANCE 1%
J 0
(-2325 4200);
DISPLAY 0.617021 (-2325 4200);
PAINT SKYBLUE (-2325 4200);
FORCEPROP 1 LASTPIN (-2300 4250) $PN 2
J 0
(-2338 4262);
DISPLAY 0.617021 (-2338 4262);
PAINT ORANGE (-2338 4262);
FORCEPROP 1 LASTPIN (-2500 4250) $PN 1
J 0
(-2488 4262);
DISPLAY 0.617021 (-2488 4262);
PAINT ORANGE (-2488 4262);
FORCEPROP 1 LAST VALUE 20.0
J 2
(-2500 4200);
DISPLAY 0.617021 (-2500 4200);
PAINT SKYBLUE (-2500 4200);
FORCEPROP 1 LAST LOCATION R2U32
J 0
(-2750 4200);
DISPLAY 0.617021 (-2750 4200);
PAINT AQUA (-2750 4200);
FORCEPROP 0 LAST BOM_COST SM_CONTROLLER
J 0
(-2150 4400);
DISPLAY 1.021277 (-2150 4400);
PAINT ORANGE (-2150 4400);
DISPLAY INVISIBLE (-2150 4400);
FORCEPROP 0 LAST ROOM SMBUS
J 0
(-2150 4300);
DISPLAY 1.021277 (-2150 4300);
PAINT ORANGE (-2150 4300);
DISPLAY INVISIBLE (-2150 4300);
FORCEPROP 0 LAST SKU B
J 0
(-2150 4300);
DISPLAY 1.021277 (-2150 4300);
PAINT ORANGE (-2150 4300);
DISPLAY INVISIBLE (-2150 4300);
FORCEPROP 1 LAST PACK_TYPE 0402
J 0
(-2250 4200);
DISPLAY 0.617021 (-2250 4200);
PAINT SKYBLUE (-2250 4200);
DISPLAY INVISIBLE (-2250 4200);
FORCEPROP 2 LAST CDS_SEC 1
J 0
(-2450 4450);
PAINT MONO (-2450 4450);
DISPLAY INVISIBLE (-2450 4450);
FORCEPROP 2 LAST $SEC 1
J 0
(-2450 4450);
PAINT MONO (-2450 4450);
DISPLAY INVISIBLE (-2450 4450);
FORCEPROP 1 LAST PATH I339
J 0
(-2450 4400);
DISPLAY 0.978723 (-2450 4400);
PAINT WHITE (-2450 4400);
DISPLAY INVISIBLE (-2450 4400);
FORCEPROP 2 LAST CDS_LIB mstr_discrete
J 0
(-2400 4250);
PAINT MONO (-2400 4250);
DISPLAY INVISIBLE (-2400 4250);
FORCEPROP 1 LAST WATTAGE 1/16W
J 2
(-2525 4200);
DISPLAY 0.617021 (-2525 4200);
PAINT SKYBLUE (-2525 4200);
DISPLAY INVISIBLE (-2525 4200);
FORCEPROP 2 LAST CDS_LOCATION R2U32
J 0
(-2650 4200);
DISPLAY 0.617021 (-2650 4200);
PAINT AQUA (-2650 4200);
DISPLAY INVISIBLE (-2650 4200);
FORCEADD RES..1
(-2400 4350);
FORCEPROP 1 LAST MATERIAL EMPTY
J 0
(-2100 4300);
DISPLAY 0.617021 (-2100 4300);
PAINT RED (-2100 4300);
FORCEPROP 1 LAST PART_NUMBER G21796-173
J 0
(-2100 4350);
DISPLAY 0.617021 (-2100 4350);
PAINT BLUE (-2100 4350);
FORCEPROP 1 LAST TOLERANCE 1%
J 0
(-2250 4300);
DISPLAY 0.617021 (-2250 4300);
PAINT SKYBLUE (-2250 4300);
FORCEPROP 1 LASTPIN (-2300 4350) $PN 2
J 0
(-2338 4362);
DISPLAY 0.617021 (-2338 4362);
PAINT ORANGE (-2338 4362);
FORCEPROP 1 LASTPIN (-2500 4350) $PN 1
J 0
(-2488 4362);
DISPLAY 0.617021 (-2488 4362);
PAINT ORANGE (-2488 4362);
FORCEPROP 1 LAST VALUE 20.0
J 2
(-2500 4300);
DISPLAY 0.617021 (-2500 4300);
PAINT SKYBLUE (-2500 4300);
FORCEPROP 1 LAST LOCATION R2U36
J 0
(-2750 4300);
DISPLAY 0.617021 (-2750 4300);
PAINT AQUA (-2750 4300);
FORCEPROP 0 LAST ROOM SMBUS
J 0
(-2150 4400);
DISPLAY 1.021277 (-2150 4400);
PAINT ORANGE (-2150 4400);
DISPLAY INVISIBLE (-2150 4400);
FORCEPROP 0 LAST SKU A
J 0
(-2150 4400);
DISPLAY 1.021277 (-2150 4400);
PAINT ORANGE (-2150 4400);
DISPLAY INVISIBLE (-2150 4400);
FORCEPROP 0 LAST BOM_COST SM_CONTROLLER
J 0
(-2150 4500);
DISPLAY 1.021277 (-2150 4500);
PAINT ORANGE (-2150 4500);
DISPLAY INVISIBLE (-2150 4500);
FORCEPROP 1 LAST PACK_TYPE 0402
J 0
(-2250 4300);
DISPLAY 0.617021 (-2250 4300);
PAINT SKYBLUE (-2250 4300);
DISPLAY INVISIBLE (-2250 4300);
FORCEPROP 2 LAST $SEC 1
J 0
(-2450 4550);
PAINT MONO (-2450 4550);
DISPLAY INVISIBLE (-2450 4550);
FORCEPROP 2 LAST CDS_SEC 1
J 0
(-2450 4550);
PAINT MONO (-2450 4550);
DISPLAY INVISIBLE (-2450 4550);
FORCEPROP 1 LAST PATH I340
J 0
(-2450 4500);
DISPLAY 0.978723 (-2450 4500);
PAINT WHITE (-2450 4500);
DISPLAY INVISIBLE (-2450 4500);
FORCEPROP 2 LAST CDS_LIB mstr_discrete
J 0
(-2400 4350);
PAINT MONO (-2400 4350);
DISPLAY INVISIBLE (-2400 4350);
FORCEPROP 1 LAST WATTAGE 1/16W
J 2
(-2525 4300);
DISPLAY 0.617021 (-2525 4300);
PAINT SKYBLUE (-2525 4300);
DISPLAY INVISIBLE (-2525 4300);
FORCEPROP 2 LAST CDS_LOCATION R2U36
J 0
(-2650 4300);
DISPLAY 0.617021 (-2650 4300);
PAINT AQUA (-2650 4300);
DISPLAY INVISIBLE (-2650 4300);
FORCEADD RES..1
(2375 3775);
FORCEPROP 1 LAST PART_NUMBER G21497-005
J 0
(2725 3725);
DISPLAY 0.617021 (2725 3725);
PAINT BLUE (2725 3725);
FORCEPROP 1 LAST PACK_TYPE 0402
J 0
(2600 3725);
DISPLAY 0.617021 (2600 3725);
PAINT SKYBLUE (2600 3725);
FORCEPROP 1 LAST MATERIAL CHIP
J 0
(2475 3725);
DISPLAY 0.617021 (2475 3725);
PAINT SKYBLUE (2475 3725);
FORCEPROP 1 LAST LOCATION R7E22
J 0
(2325 3825);
DISPLAY 0.617021 (2325 3825);
PAINT AQUA (2325 3825);
FORCEPROP 1 LASTPIN (2475 3775) $PN 2
J 0
(2437 3787);
DISPLAY 0.617021 (2437 3787);
PAINT ORANGE (2437 3787);
FORCEPROP 1 LAST TOLERANCE 5%
J 0
(2375 3725);
DISPLAY 0.617021 (2375 3725);
PAINT SKYBLUE (2375 3725);
FORCEPROP 1 LAST VALUE 0.0
J 2
(2325 3725);
DISPLAY 0.617021 (2325 3725);
PAINT SKYBLUE (2325 3725);
FORCEPROP 1 LASTPIN (2275 3775) $PN 1
J 0
(2287 3787);
DISPLAY 0.617021 (2287 3787);
PAINT ORANGE (2287 3787);
FORCEPROP 1 LAST WATTAGE 1/16W
J 2
(2225 3725);
DISPLAY 0.617021 (2225 3725);
PAINT SKYBLUE (2225 3725);
FORCEPROP 2 LAST SEC_TYPE 0402
J 0
(2325 3975);
DISPLAY 1.021277 (2325 3975);
PAINT ORANGE (2325 3975);
DISPLAY INVISIBLE (2325 3975);
FORCEPROP 2 LAST SEC 1
J 0
(2325 3975);
DISPLAY 0.680851 (2325 3975);
PAINT MONO (2325 3975);
DISPLAY INVISIBLE (2325 3975);
FORCEPROP 1 LAST PATH I341
J 0
(2325 3925);
DISPLAY 0.978723 (2325 3925);
PAINT WHITE (2325 3925);
DISPLAY INVISIBLE (2325 3925);
FORCEPROP 0 LAST ROOM IO_SLOT
J 0
(2325 3975);
DISPLAY 1.021277 (2325 3975);
PAINT ORANGE (2325 3975);
DISPLAY INVISIBLE (2325 3975);
FORCEPROP 2 LAST CDS_LIB mstr_discrete
J 0
(2375 3775);
PAINT ORANGE (2375 3775);
DISPLAY INVISIBLE (2375 3775);
FORCEADD OFFPAGE..1
(1875 3775);
FORCEPROP 2 LAST $XR0 95 
J 0
(1654 3775);
DISPLAY 0.638298 (1654 3775);
PAINT MONO (1654 3775);
FORCEPROP 1 LAST OFFPAGE TRUE
J 0
(2200 3650);
DISPLAY 0.872340 (2200 3650);
PAINT GREEN (2200 3650);
DISPLAY INVISIBLE (2200 3650);
FORCEPROP 2 LAST CDS_LIB mstr_standard
J 0
(1875 3775);
PAINT ORANGE (1875 3775);
DISPLAY INVISIBLE (1875 3775);
FORCEPROP 1 LAST COMMENT_BODY TRUE
J 0
(2000 3675);
DISPLAY 0.872340 (2000 3675);
PAINT GREEN (2000 3675);
DISPLAY INVISIBLE (2000 3675);
FORCEPROP 2 LAST PATH I342
J 0
(1925 3850);
DISPLAY 1.021277 (1925 3850);
PAINT ORANGE (1925 3850);
DISPLAY INVISIBLE (1925 3850);
FORCEADD RES..2
(2225 4300);
FORCEPROP 1 LAST LOCATION R7E21
J 0
(2270 4425);
DISPLAY 0.617021 (2270 4425);
PAINT AQUA (2270 4425);
FORCEPROP 1 LAST PART_NUMBER G21796-072
J 0
(2265 4175);
DISPLAY 0.617021 (2265 4175);
PAINT BLUE (2265 4175);
FORCEPROP 1 LAST VALUE 4.75K
J 0
(2270 4375);
DISPLAY 0.617021 (2270 4375);
PAINT SKYBLUE (2270 4375);
FORCEPROP 1 LAST TOLERANCE 1%
J 0
(2270 4325);
DISPLAY 0.617021 (2270 4325);
PAINT SKYBLUE (2270 4325);
FORCEPROP 1 LAST PACK_TYPE 0402
J 0
(2265 4125);
DISPLAY 0.617021 (2265 4125);
PAINT SKYBLUE (2265 4125);
FORCEPROP 1 LAST MATERIAL CHIP
J 0
(2265 4225);
DISPLAY 0.617021 (2265 4225);
PAINT SKYBLUE (2265 4225);
FORCEPROP 1 LAST WATTAGE 1/16W
J 0
(2265 4275);
DISPLAY 0.617021 (2265 4275);
PAINT SKYBLUE (2265 4275);
FORCEPROP 1 LASTPIN (2225 4400) $PN 1
J 0
(2230 4362);
DISPLAY 0.617021 (2230 4362);
PAINT ORANGE (2230 4362);
FORCEPROP 1 LASTPIN (2225 4200) $PN 2
J 0
(2230 4210);
DISPLAY 0.617021 (2230 4210);
PAINT ORANGE (2230 4210);
FORCEPROP 2 LAST SEC_TYPE 0402
J 0
(2275 4525);
DISPLAY 1.021277 (2275 4525);
PAINT ORANGE (2275 4525);
DISPLAY INVISIBLE (2275 4525);
FORCEPROP 2 LAST SEC 1
J 0
(2275 4525);
DISPLAY 0.680851 (2275 4525);
PAINT MONO (2275 4525);
DISPLAY INVISIBLE (2275 4525);
FORCEPROP 0 LAST ROOM IO_SLOT
J 0
(2275 4525);
DISPLAY 1.021277 (2275 4525);
PAINT ORANGE (2275 4525);
DISPLAY INVISIBLE (2275 4525);
FORCEPROP 1 LAST PATH I343
J 0
(2275 4475);
DISPLAY 0.978723 (2275 4475);
PAINT WHITE (2275 4475);
DISPLAY INVISIBLE (2275 4475);
FORCEPROP 2 LAST CDS_LIB mstr_discrete
J 0
(2225 4300);
PAINT ORANGE (2225 4300);
DISPLAY INVISIBLE (2225 4300);
FORCEADD P3V3..1
(2225 4550);
FORCEPROP 3 LASTPIN (2225 4500) SIG_NAME P3V3\g
J 0
(2235 4510);
DISPLAY 0.659574 (2235 4510);
PAINT MONO (2235 4510);
DISPLAY INVISIBLE (2235 4510);
FORCEPROP 1 LAST VOLTAGE 3.3V
J 0
(2180 4507);
DISPLAY 0.340426 (2180 4507);
PAINT SKYBLUE (2180 4507);
DISPLAY INVISIBLE (2180 4507);
FORCEPROP 2 LAST CDS_LIB mstr_symbols
J 0
(2225 4550);
PAINT ORANGE (2225 4550);
DISPLAY INVISIBLE (2225 4550);
FORCEPROP 1 LAST SIZE 1B
J 0
(2270 4572);
DISPLAY 0.340426 (2270 4572);
PAINT GREEN (2270 4572);
DISPLAY INVISIBLE (2270 4572);
FORCEPROP 1 LAST BODY_TYPE PLUMBING
J 0
(2180 4507);
DISPLAY 0.340426 (2180 4507);
PAINT GREEN (2180 4507);
DISPLAY INVISIBLE (2180 4507);
FORCEPROP 1 LAST PATH I344
J 0
(2270 4552);
DISPLAY 0.340426 (2270 4552);
PAINT GREEN (2270 4552);
DISPLAY INVISIBLE (2270 4552);
FORCEPROP 1 LAST HDL_POWER P3V3
J 0
(1900 4425);
DISPLAY 0.872340 (1900 4425);
PAINT ORANGE (1900 4425);
DISPLAY INVISIBLE (1900 4425);
FORCEADD TAP..1
(1500 1875);
FORCEPROP 3 LASTPIN (1450 1875) SIG_NAME P3E_CPU0_PE1_PCH_CON_RXN<8>
J 0
(1460 1885);
DISPLAY 0.659574 (1460 1885);
PAINT MONO (1460 1885);
DISPLAY INVISIBLE (1460 1885);
FORCEPROP 1 LASTPIN (1450 1875) BN 8
J 0
(1438 1883);
DISPLAY 0.617021 (1438 1883);
PAINT GREEN (1438 1883);
FORCEPROP 2 LAST CDS_LIB mstr_standard
J 0
(1500 1875);
PAINT MONO (1500 1875);
DISPLAY INVISIBLE (1500 1875);
FORCEPROP 1 LAST BODY_TYPE PLUMBING
J 0
(1500 1925);
DISPLAY 0.638298 (1500 1925);
PAINT GREEN (1500 1925);
DISPLAY INVISIBLE (1500 1925);
FORCEPROP 1 LAST HDL_TAP TRUE
J 0
(1825 1750);
DISPLAY 0.638298 (1825 1750);
PAINT GREEN (1825 1750);
DISPLAY INVISIBLE (1825 1750);
FORCEPROP 1 LAST PATH I345
J 0
(1498 1875);
DISPLAY 0.872340 (1498 1875);
PAINT GREEN (1498 1875);
DISPLAY INVISIBLE (1498 1875);
FORCEADD P12V..1
(-3275 925);
FORCEPROP 3 LASTPIN (-3275 875) SIG_NAME P12V\g
J 0
(-3265 885);
DISPLAY 0.659574 (-3265 885);
PAINT MONO (-3265 885);
DISPLAY INVISIBLE (-3265 885);
FORCEPROP 2 LAST CDS_LIB mstr_symbols
J 0
(-3275 925);
PAINT MONO (-3275 925);
DISPLAY INVISIBLE (-3275 925);
FORCEPROP 1 LAST SIZE 1B
J 0
(-3230 947);
DISPLAY 0.340426 (-3230 947);
PAINT GREEN (-3230 947);
DISPLAY INVISIBLE (-3230 947);
FORCEPROP 1 LAST VOLTAGE +12.
J 0
(-3275 925);
PAINT SKYBLUE (-3275 925);
DISPLAY INVISIBLE (-3275 925);
FORCEPROP 1 LAST PATH I4
J 0
(-3230 927);
DISPLAY 0.340426 (-3230 927);
PAINT GREEN (-3230 927);
DISPLAY INVISIBLE (-3230 927);
FORCEPROP 1 LAST BODY_TYPE PLUMBING
J 0
(-3320 882);
DISPLAY 0.340426 (-3320 882);
PAINT GREEN (-3320 882);
DISPLAY INVISIBLE (-3320 882);
FORCEPROP 1 LAST HDL_POWER P12V
J 0
(-3475 775);
DISPLAY 0.872340 (-3475 775);
PAINT ORANGE (-3475 775);
DISPLAY INVISIBLE (-3475 775);
FORCEADD CAP_A..1
(-3275 1400);
FORCEPROP 1 LAST PART_NUMBER A36096-030
J 0
(-3225 1250);
DISPLAY 0.617021 (-3225 1250);
PAINT BLUE (-3225 1250);
FORCEPROP 1 LAST MATERIAL X7R
J 0
(-3225 1300);
DISPLAY 0.617021 (-3225 1300);
PAINT SKYBLUE (-3225 1300);
FORCEPROP 1 LAST VOLTAGE 16V
J 0
(-3225 1400);
DISPLAY 0.617021 (-3225 1400);
PAINT SKYBLUE (-3225 1400);
FORCEPROP 1 LAST TOLERANCE 10%
J 0
(-3225 1350);
DISPLAY 0.617021 (-3225 1350);
PAINT SKYBLUE (-3225 1350);
FORCEPROP 1 LAST LOCATION C2U21
J 0
(-3225 1500);
DISPLAY 0.617021 (-3225 1500);
PAINT AQUA (-3225 1500);
FORCEPROP 1 LAST VALUE 0.1UF
J 0
(-3225 1450);
DISPLAY 0.617021 (-3225 1450);
PAINT SKYBLUE (-3225 1450);
FORCEPROP 1 LASTPIN (-3275 1500) $PN 1
J 0
(-3265 1480);
DISPLAY 0.617021 (-3265 1480);
PAINT ORANGE (-3265 1480);
FORCEPROP 1 LASTPIN (-3275 1300) $PN 2
J 0
(-3265 1280);
DISPLAY 0.617021 (-3265 1280);
PAINT ORANGE (-3265 1280);
FORCEPROP 1 LAST PACK_TYPE 0402V
J 0
(-3225 1200);
DISPLAY 0.617021 (-3225 1200);
PAINT SKYBLUE (-3225 1200);
FORCEPROP 2 LAST SEC_TYPE 0402V
J 0
(-3225 1600);
DISPLAY 1.021277 (-3225 1600);
PAINT ORANGE (-3225 1600);
DISPLAY INVISIBLE (-3225 1600);
FORCEPROP 2 LAST SEC 1
J 0
(-3225 1600);
DISPLAY 0.680851 (-3225 1600);
PAINT MONO (-3225 1600);
DISPLAY INVISIBLE (-3225 1600);
FORCEPROP 2 LAST CDS_SEC 1
J 0
(-3225 1550);
PAINT ORANGE (-3225 1550);
DISPLAY INVISIBLE (-3225 1550);
FORCEPROP 0 LAST ROOM IO_SLOT
J 0
(-3225 1600);
DISPLAY 1.021277 (-3225 1600);
PAINT ORANGE (-3225 1600);
DISPLAY INVISIBLE (-3225 1600);
FORCEPROP 1 LAST PATH I5
J 0
(-3225 1550);
DISPLAY 0.978723 (-3225 1550);
PAINT WHITE (-3225 1550);
DISPLAY INVISIBLE (-3225 1550);
FORCEPROP 2 LAST CDS_LIB dev_discrete
J 0
(-3275 1400);
PAINT ORANGE (-3275 1400);
DISPLAY INVISIBLE (-3275 1400);
FORCEPROP 2 LAST CDS_LOCATION C2U21
J 0
(-3225 1500);
DISPLAY 0.617021 (-3225 1500);
PAINT AQUA (-3225 1500);
DISPLAY INVISIBLE (-3225 1500);
FORCEADD CAP_A..1
(-2875 1375);
FORCEPROP 1 LASTPIN (-2875 1475) $PN 1
J 0
(-2865 1455);
DISPLAY 0.617021 (-2865 1455);
PAINT ORANGE (-2865 1455);
FORCEPROP 1 LAST LOCATION C2U25
J 0
(-2825 1475);
DISPLAY 0.617021 (-2825 1475);
PAINT AQUA (-2825 1475);
FORCEPROP 1 LAST VOLTAGE 16V
J 0
(-2825 1375);
DISPLAY 0.617021 (-2825 1375);
PAINT SKYBLUE (-2825 1375);
FORCEPROP 1 LAST VALUE 0.1UF
J 0
(-2825 1425);
DISPLAY 0.617021 (-2825 1425);
PAINT SKYBLUE (-2825 1425);
FORCEPROP 1 LAST PART_NUMBER A36096-030
J 0
(-2825 1225);
DISPLAY 0.617021 (-2825 1225);
PAINT BLUE (-2825 1225);
FORCEPROP 1 LAST PACK_TYPE 0402V
J 0
(-2825 1175);
DISPLAY 0.617021 (-2825 1175);
PAINT SKYBLUE (-2825 1175);
FORCEPROP 1 LAST TOLERANCE 10%
J 0
(-2825 1325);
DISPLAY 0.617021 (-2825 1325);
PAINT SKYBLUE (-2825 1325);
FORCEPROP 1 LAST MATERIAL X7R
J 0
(-2825 1275);
DISPLAY 0.617021 (-2825 1275);
PAINT SKYBLUE (-2825 1275);
FORCEPROP 1 LASTPIN (-2875 1275) $PN 2
J 0
(-2865 1255);
DISPLAY 0.617021 (-2865 1255);
PAINT ORANGE (-2865 1255);
FORCEPROP 2 LAST SEC 1
J 0
(-2825 1575);
DISPLAY 0.680851 (-2825 1575);
PAINT MONO (-2825 1575);
DISPLAY INVISIBLE (-2825 1575);
FORCEPROP 2 LAST SEC_TYPE 0402V
J 0
(-2825 1575);
DISPLAY 1.021277 (-2825 1575);
PAINT ORANGE (-2825 1575);
DISPLAY INVISIBLE (-2825 1575);
FORCEPROP 0 LAST ROOM IO_SLOT
J 0
(-2825 1575);
DISPLAY 1.021277 (-2825 1575);
PAINT ORANGE (-2825 1575);
DISPLAY INVISIBLE (-2825 1575);
FORCEPROP 2 LAST CDS_SEC 1
J 0
(-2825 1525);
PAINT ORANGE (-2825 1525);
DISPLAY INVISIBLE (-2825 1525);
FORCEPROP 1 LAST PATH I7
J 0
(-2825 1525);
DISPLAY 0.978723 (-2825 1525);
PAINT WHITE (-2825 1525);
DISPLAY INVISIBLE (-2825 1525);
FORCEPROP 2 LAST CDS_LOCATION C2U25
J 0
(-2825 1475);
DISPLAY 0.617021 (-2825 1475);
PAINT AQUA (-2825 1475);
DISPLAY INVISIBLE (-2825 1475);
FORCEPROP 2 LAST CDS_LIB dev_discrete
J 0
(-2875 1375);
PAINT ORANGE (-2875 1375);
DISPLAY INVISIBLE (-2875 1375);
FORCEADD DNS..2
(-2395 4595);
PAINT RED (-2395 4595);
FORCEPROP 2 LAST CDS_LIB mstr_misc
J 0
(-2395 4595);
PAINT ORANGE (-2395 4595);
DISPLAY INVISIBLE (-2395 4595);
FORCEPROP 1 LAST COMMENT_BODY TRUE
R 1
J 0
(-2320 4370);
DISPLAY 0.872340 (-2320 4370);
PAINT GREEN (-2320 4370);
DISPLAY INVISIBLE (-2320 4370);
FORCEADD DNS..2
(-2395 4345);
PAINT RED (-2395 4345);
FORCEPROP 2 LAST CDS_LIB mstr_misc
J 0
(-2395 4345);
PAINT ORANGE (-2395 4345);
DISPLAY INVISIBLE (-2395 4345);
FORCEPROP 1 LAST COMMENT_BODY TRUE
R 1
J 0
(-2320 4120);
DISPLAY 0.872340 (-2320 4120);
PAINT GREEN (-2320 4120);
DISPLAY INVISIBLE (-2320 4120);
FORCEADD CAD_NOTE..1
(-3175 4850);
FORCEPROP 0 LAST L1 USE SHARED PADS FOR THESE RESISTORS
J 0
(-3325 4750);
DISPLAY 0.808511 (-3325 4750);
PAINT ORANGE (-3325 4750);
FORCEPROP 0 LAST L2 PLACE CLOSE TO X24 SLOT
J 0
(-3325 4700);
DISPLAY 0.808511 (-3325 4700);
PAINT ORANGE (-3325 4700);
FORCEPROP 2 LAST CDS_LIB mstr_symbols
J 0
(-3175 4850);
PAINT MONO (-3175 4850);
DISPLAY INVISIBLE (-3175 4850);
FORCEPROP 1 LAST COMMENT_BODY TRUE
J 0
(-3150 4950);
DISPLAY 0.978723 (-3150 4950);
PAINT ORANGE (-3150 4950);
DISPLAY INVISIBLE (-3150 4950);
FORCEADD INTEL_CORP_BPAGE..1
(4400 50);
FORCEPROP 1 LAST CDS_CON_LAST_MODIFIED Tue Dec 01 11:51:53 2015
J 0
(2975 375);
PAINT ORANGE (2975 375);
DISPLAY INVISIBLE (2975 375);
FORCEPROP 1 LAST CUSTOM_TXT_CDS <CURRENT_DESIGN_SHEET> OF <TOTAL_DESIGN_SHEETS>
J 0
(3900 75);
PAINT GREEN (3900 75);
FORCEPROP 1 LAST CUSTOM_TXT_CDS <CON_LAST_MODIFIED>
J 0
(2475 400);
PAINT GREEN (2475 400);
FORCEPROP 2 LAST CUSTOM_TXT_CDS <XR_PAGE_TITLE>
J 0
(-3490 5300);
DISPLAY 0.638298 (-3490 5300);
PAINT PINK (-3490 5300);
DISPLAY INVISIBLE (-3490 5300);
FORCEPROP 1 LAST SCH_ADDRESS1 2200 Mission College Blvd.
J 0
(425 175);
DISPLAY 0.617021 (425 175);
PAINT GREEN (425 175);
FORCEPROP 1 LAST SCH_ADDRESS2 P.O. BOX 58119
J 0
(425 125);
DISPLAY 0.617021 (425 125);
PAINT GREEN (425 125);
FORCEPROP 1 LAST SCH_ADDRESS3 Santa Clara, CA 95052-8119
J 0
(425 75);
DISPLAY 0.617021 (425 75);
PAINT GREEN (425 75);
FORCEPROP 1 LAST SCH_NUMBER H4694802
J 0
(3100 200);
DISPLAY 1.212766 (3100 200);
PAINT YELLOW (3100 200);
FORCEPROP 1 LAST SCH_REV 2.420
J 0
(4150 200);
DISPLAY 0.978723 (4150 200);
PAINT YELLOW (4150 200);
FORCEPROP 1 LAST SCH_DEPT BESD
J 1
(-50 150);
DISPLAY 1.212766 (-50 150);
PAINT YELLOW (-50 150);
FORCEPROP 1 LAST SCH_TITLE X24 SLOT (1 OF 2)
J 0
(-3550 100);
DISPLAY 1.212766 (-3550 100);
PAINT ORANGE (-3550 100);
FORCEPROP 2 LAST CDS_LIB mstr_symbols
J 0
(4400 50);
PAINT MONO (4400 50);
DISPLAY INVISIBLE (4400 50);
FORCEPROP 1 LAST COMMENT_BODY TRUE
J 0
(4412 62);
DISPLAY 0.468085 (4412 62);
PAINT GREEN (4412 62);
DISPLAY INVISIBLE (4412 62);
FORCEPROP 2 LAST PAGE_BORDER TRUE
J 0
(-3490 5300);
DISPLAY 0.638298 (-3490 5300);
PAINT PINK (-3490 5300);
DISPLAY INVISIBLE (-3490 5300);
FORCEPROP 2 LAST CDS_XR_PAGE_TITLE CR-108 : @BASEBOARD_FAB2_LIB.BASEBOARD_FAB2(SCH_1):PAGE108
J 0
(-3490 5300);
DISPLAY 0.638298 (-3490 5300);
PAINT PINK (-3490 5300);
DISPLAY INVISIBLE (-3490 5300);
WIRE 17 -1 (-600 3100)(-600 3075);
WIRE 17 -1 (-600 3075)(-600 2900);
WIRE 17 -1 (-600 3075)(-2575 3075);
FORCEPROP 2 LAST SIG_NAME P3E_CPU0_PE1_PCH_CON_TXN<15:8>
J 0
(-2490 3073);
DISPLAY 0.680851 (-2490 3073);
PAINT ORANGE (-2490 3073);
WIRE 17 -1 (-600 2550)(-600 2400);
WIRE 17 -1 (-600 2700)(-600 2550);
WIRE 17 -1 (-600 2400)(-600 2250);
WIRE 17 -1 (-600 2250)(-600 2100);
WIRE 17 -1 (-600 2900)(-600 2700);
WIRE 17 -1 (-600 2100)(-600 1950);
WIRE 17 -1 (1400 2450)(1400 2300);
WIRE 17 -1 (1400 2600)(1400 2450);
WIRE 17 -1 (1400 2300)(1400 2150);
WIRE 17 -1 (1400 2150)(1400 2050);
WIRE 17 -1 (1400 2850)(1400 2600);
WIRE 17 -1 (1400 3000)(1400 2850);
WIRE 17 -1 (1400 3075)(1400 3000);
WIRE 17 -1 (1400 3075)(2800 3075);
FORCEPROP 2 LAST SIG_NAME P3E_CPU0_PE1_PCH_CON_RXP<15:8>
J 0
(1465 3085);
DISPLAY 0.680851 (1465 3085);
PAINT ORANGE (1465 3085);
WIRE 17 -1 (1550 2900)(1550 2650);
WIRE 17 -1 (1550 2900)(1550 2975);
WIRE 17 -1 (1550 2650)(1550 2500);
WIRE 17 -1 (1550 2500)(1550 2350);
WIRE 17 -1 (1550 2975)(2775 2975);
FORCEPROP 2 LAST SIG_NAME P3E_CPU0_PE1_PCH_CON_RXN<15:8>
J 0
(1565 2985);
DISPLAY 0.680851 (1565 2985);
PAINT ORANGE (1565 2985);
WIRE 17 -1 (-800 2950)(-800 2650);
WIRE 17 -1 (-800 3050)(-800 2950);
WIRE 17 -1 (-800 2650)(-800 2500);
WIRE 17 -1 (-800 2500)(-800 2350);
WIRE 17 -1 (-800 3125)(-800 3050);
WIRE 17 -1 (-2575 3125)(-800 3125);
FORCEPROP 2 LAST SIG_NAME P3E_CPU0_PE1_PCH_CON_TXP<15:8>
J 0
(-2490 3133);
DISPLAY 0.680851 (-2490 3133);
PAINT ORANGE (-2490 3133);
WIRE 17 -1 (-800 2350)(-800 2200);
WIRE 17 -1 (-800 2200)(-800 2050);
WIRE 17 -1 (-800 2050)(-800 1900);
WIRE 17 -1 (1550 3050)(1550 2975);
WIRE 17 -1 (1550 2350)(1550 2200);
WIRE 17 -1 (1550 2200)(1550 2000);
WIRE 17 -1 (1550 2000)(1550 1900);
WIRE 16 -1 (1375 4125)(1375 4075);
WIRE 16 -1 (1375 4175)(1375 4125);
WIRE 16 -1 (1375 4125)(800 4125);
WIRE 16 -1 (1375 4075)(800 4075);
WIRE 16 -1 (1375 4225)(1375 4175);
WIRE 16 -1 (1375 4175)(800 4175);
WIRE 16 -1 (1375 4275)(1375 4225);
WIRE 16 -1 (1375 4225)(800 4225);
WIRE 16 -1 (1375 4325)(1375 4275);
WIRE 16 -1 (1375 4275)(800 4275);
WIRE 16 -1 (1375 4625)(1375 4325);
WIRE 16 -1 (1375 4325)(800 4325);
WIRE 16 -1 (-350 4075)(200 4075);
WIRE 16 -1 (-350 4125)(-350 4075);
WIRE 16 -1 (-350 4125)(200 4125);
WIRE 16 -1 (-350 4175)(-350 4125);
WIRE 16 -1 (-350 4175)(200 4175);
WIRE 16 -1 (-350 4225)(-350 4175);
WIRE 16 -1 (-350 4225)(200 4225);
WIRE 16 -1 (-350 4275)(-350 4225);
WIRE 16 -1 (-350 4275)(200 4275);
WIRE 16 -1 (-350 4275)(-350 4325);
WIRE 16 -1 (-350 4325)(200 4325);
WIRE 16 -1 (-350 4675)(-350 4325);
WIRE 16 -1 (-100 4025)(200 4025);
WIRE 16 -1 (-100 3575)(-100 4025);
WIRE 16 -1 (-100 3575)(200 3575);
WIRE 16 -1 (-100 3425)(-100 3575);
WIRE 16 -1 (200 3425)(-100 3425);
WIRE 16 -1 (-100 3425)(-100 3275);
WIRE 16 -1 (200 3275)(-100 3275);
WIRE 16 -1 (-100 3275)(-100 3125);
WIRE 16 -1 (200 3125)(-100 3125);
WIRE 16 -1 (-100 2975)(-100 3125);
WIRE 16 -1 (200 2975)(-100 2975);
WIRE 16 -1 (-100 2975)(-100 2825);
WIRE 16 -1 (200 2825)(-100 2825);
WIRE 16 -1 (-100 2825)(-100 2725);
WIRE 16 -1 (200 2725)(-100 2725);
WIRE 16 -1 (-100 2725)(-100 2575);
WIRE 16 -1 (200 2575)(-100 2575);
WIRE 16 -1 (-100 2575)(-100 2425);
WIRE 16 -1 (200 2425)(-100 2425);
WIRE 16 -1 (-100 2275)(-100 2425);
WIRE 16 -1 (200 2275)(-100 2275);
WIRE 16 -1 (-100 2275)(-100 2125);
WIRE 16 -1 (200 2125)(-100 2125);
WIRE 16 -1 (-100 2125)(-100 1975);
WIRE 16 -1 (200 1975)(-100 1975);
WIRE 16 -1 (-100 1825)(-100 1975);
WIRE 16 -1 (-100 1825)(200 1825);
WIRE 16 -1 (-100 1275)(-100 1825);
WIRE 16 -1 (-525 3775)(200 3775);
WIRE 16 -1 (-525 3825)(-525 3775);
WIRE 16 -1 (200 3825)(-525 3825);
WIRE 16 -1 (-525 4575)(-525 3825);
WIRE 16 -1 (1050 3725)(1050 4025);
WIRE 16 -1 (1050 3525)(1050 3725);
WIRE 16 -1 (1050 3725)(800 3725);
WIRE 16 -1 (1050 4025)(800 4025);
WIRE 16 -1 (1050 3525)(1050 3375);
WIRE 16 -1 (1050 3525)(800 3525);
WIRE 16 -1 (1050 3375)(1050 3225);
WIRE 16 -1 (1050 3375)(800 3375);
WIRE 16 -1 (1050 3075)(1050 3225);
WIRE 16 -1 (1050 3225)(800 3225);
WIRE 16 -1 (1050 3075)(1050 2925);
WIRE 16 -1 (1050 3075)(800 3075);
WIRE 16 -1 (1050 2925)(1050 2775);
WIRE 16 -1 (1050 2925)(800 2925);
WIRE 16 -1 (1050 2775)(1050 2675);
WIRE 16 -1 (1050 2775)(800 2775);
WIRE 16 -1 (1050 2675)(1050 2525);
WIRE 16 -1 (1050 2675)(800 2675);
WIRE 16 -1 (1050 2375)(1050 2525);
WIRE 16 -1 (1050 2525)(800 2525);
WIRE 16 -1 (1050 2375)(1050 2225);
WIRE 16 -1 (1050 2375)(800 2375);
WIRE 16 -1 (1050 2075)(1050 2225);
WIRE 16 -1 (1050 2225)(800 2225);
WIRE 16 -1 (1050 2075)(800 2075);
WIRE 16 -1 (1050 2075)(1050 1925);
WIRE 16 -1 (1050 1825)(1050 1925);
WIRE 16 -1 (1050 1925)(800 1925);
WIRE 16 -1 (800 1825)(1050 1825);
WIRE 16 -1 (1050 1275)(1050 1825);
WIRE 16 -1 (1600 3825)(1600 3775);
WIRE 16 -1 (800 3825)(1600 3825);
WIRE 16 -1 (1600 4625)(1600 3825);
WIRE 16 -1 (1600 3775)(800 3775);
WIRE 16 -1 (-3275 575)(-3275 400);
WIRE 16 -1 (-3275 400)(-2875 400);
WIRE 16 -1 (-2875 400)(-2875 550);
WIRE 16 -1 (-2875 400)(-2875 350);
WIRE 16 -1 (-2875 1575)(-2875 1475);
WIRE 16 -1 (-3275 1575)(-2875 1575);
WIRE 16 -1 (-3275 1500)(-3275 1575);
WIRE 16 -1 (-3275 1575)(-3275 1600);
WIRE 16 -1 (-2875 1100)(-3275 1100);
WIRE 16 -1 (-2875 1275)(-2875 1100);
WIRE 16 -1 (-2875 1100)(-2875 1025);
WIRE 16 -1 (-3275 1100)(-3275 1300);
WIRE 16 -1 (200 3725)(-25 3725);
WIRE 16 -1 (-25 3725)(-25 4575);
WIRE 16 -1 (-1950 1075)(-2350 1075);
WIRE 16 -1 (-1950 1250)(-1950 1075);
WIRE 16 -1 (-1950 1075)(-1950 1000);
WIRE 16 -1 (-2350 1075)(-2350 1275);
WIRE 16 -1 (-1950 1550)(-1950 1450);
WIRE 16 -1 (-2350 1550)(-1950 1550);
WIRE 16 -1 (-2350 1475)(-2350 1550);
WIRE 16 -1 (-2350 1550)(-2350 1575);
WIRE 16 -1 (2225 4500)(2225 4400);
WIRE 16 -1 (-2875 850)(-2875 750);
WIRE 16 -1 (-3275 850)(-2875 850);
WIRE 16 -1 (-3275 850)(-3275 775);
WIRE 16 -1 (-3275 875)(-3275 850);
WIRE 16 3135 (-2150 4950)(-3425 4950);
WIRE 16 3135 (-2150 4050)(-2150 4950);
WIRE 16 3135 (-3425 4950)(-3425 4050);
WIRE 16 3135 (-3425 4050)(-2150 4050);
WIRE 3 2175 (-2950 3550)(3375 3550);
WIRE 3 2175 (-2950 3550)(-2950 1775);
WIRE 3 2175 (3375 3550)(3375 1775);
WIRE 3 2175 (-2950 1775)(3375 1775);
WIRE 16 -1 (800 1875)(1450 1875);
WIRE 16 -1 (800 1975)(1450 1975);
WIRE 16 -1 (800 2025)(1300 2025);
WIRE 16 -1 (800 2175)(1450 2175);
WIRE 16 -1 (800 2325)(1450 2325);
WIRE 16 -1 (800 2425)(1300 2425);
WIRE 16 -1 (800 2475)(1450 2475);
WIRE 16 -1 (800 2725)(2250 2725);
FORCEPROP 0 LAST SIG_NAME FM_PRSNT_2_5_N
J 0
(1600 2735);
DISPLAY 0.617021 (1600 2735);
PAINT ORANGE (1600 2735);
WIRE 16 -1 (800 2875)(1450 2875);
WIRE 16 -1 (800 2575)(1300 2575);
WIRE 16 -1 (800 2825)(1300 2825);
WIRE 16 -1 (800 2975)(1300 2975);
WIRE 16 -1 (800 3025)(1450 3025);
WIRE 16 -1 (-700 1875)(200 1875);
WIRE 16 -1 (200 2025)(-700 2025);
WIRE 16 -1 (-700 2175)(200 2175);
WIRE 16 -1 (200 2325)(-700 2325);
WIRE 16 -1 (-700 2475)(200 2475);
WIRE 16 -1 (-1500 2775)(200 2775);
FORCEPROP 0 LAST SIG_NAME FM_PRSNT_2_4_N
J 0
(-1375 2785);
DISPLAY 0.617021 (-1375 2785);
PAINT ORANGE (-1375 2785);
WIRE 16 -1 (200 2925)(-700 2925);
WIRE 16 -1 (200 3025)(-700 3025);
WIRE 16 -1 (-500 2875)(200 2875);
WIRE 16 -1 (-1475 3175)(200 3175);
FORCEPROP 0 LAST SIG_NAME CLK_100M_PCH_SLOTX24_S3_DN
J 0
(-1435 3185);
DISPLAY 0.617021 (-1435 3185);
PAINT ORANGE (-1435 3185);
WIRE 16 -1 (200 3225)(-1475 3225);
FORCEPROP 0 LAST SIG_NAME CLK_100M_PCH_SLOTX24_S3_DP
J 0
(-1435 3235);
DISPLAY 0.617021 (-1435 3235);
PAINT ORANGE (-1435 3235);
WIRE 16 -1 (-1475 3325)(200 3325);
FORCEPROP 0 LAST SIG_NAME CLK_100M_PCH_SLOTX24_S0_DN
J 0
(-1435 3335);
DISPLAY 0.617021 (-1435 3335);
PAINT ORANGE (-1435 3335);
WIRE 16 -1 (-1475 3375)(200 3375);
FORCEPROP 0 LAST SIG_NAME CLK_100M_PCH_SLOTX24_S0_DP
J 0
(-1435 3385);
DISPLAY 0.617021 (-1435 3385);
PAINT ORANGE (-1435 3385);
WIRE 16 -1 (-1475 3425)(-250 3425);
FORCEPROP 0 LAST SIG_NAME CLK_100M_PCH_SLOTX24_S5_DN
J 0
(-1435 3435);
DISPLAY 0.617021 (-1435 3435);
PAINT ORANGE (-1435 3435);
WIRE 16 -1 (-250 3425)(-250 3475);
WIRE 16 -1 (-250 3475)(200 3475);
WIRE 16 -1 (-1475 3475)(-325 3475);
FORCEPROP 0 LAST SIG_NAME CLK_100M_PCH_SLOTX24_S5_DP
J 0
(-1435 3485);
DISPLAY 0.617021 (-1435 3485);
PAINT ORANGE (-1435 3485);
WIRE 16 -1 (-325 3475)(-325 3525);
WIRE 16 -1 (-325 3525)(200 3525);
WIRE 16 -1 (800 3125)(2250 3125);
FORCEPROP 0 LAST SIG_NAME CLK_100M_PCH_SLOTX24_S2_DN
J 0
(1415 3135);
DISPLAY 0.617021 (1415 3135);
PAINT ORANGE (1415 3135);
WIRE 16 -1 (800 3175)(2250 3175);
FORCEPROP 0 LAST SIG_NAME CLK_100M_PCH_SLOTX24_S2_DP
J 0
(1415 3185);
DISPLAY 0.617021 (1415 3185);
PAINT ORANGE (1415 3185);
WIRE 16 -1 (800 2125)(1300 2125);
WIRE 16 -1 (-500 2675)(200 2675);
WIRE 16 -1 (-700 2625)(200 2625);
WIRE 16 -1 (-500 2525)(200 2525);
WIRE 16 -1 (1450 2625)(800 2625);
WIRE 16 -1 (800 3275)(2250 3275);
FORCEPROP 0 LAST SIG_NAME CLK_100M_PCH_SLOTX24_S1_DN
J 0
(1415 3285);
DISPLAY 0.617021 (1415 3285);
PAINT ORANGE (1415 3285);
WIRE 16 -1 (800 3475)(2250 3475);
FORCEPROP 0 LAST SIG_NAME CLK_100M_PCH_SLOTX24_S4_DP
J 0
(1290 3485);
DISPLAY 0.617021 (1290 3485);
PAINT ORANGE (1290 3485);
WIRE 16 -1 (800 3575)(2275 3575);
FORCEPROP 0 LAST SIG_NAME FM_PRSNT_2_3_N
J 0
(1400 3585);
DISPLAY 0.617021 (1400 3585);
PAINT ORANGE (1400 3585);
WIRE 16 -1 (800 3625)(2275 3625);
FORCEPROP 0 LAST SIG_NAME FM_PRSNT_2_2_N
J 0
(1400 3635);
DISPLAY 0.617021 (1400 3635);
PAINT ORANGE (1400 3635);
WIRE 16 -1 (-525 3625)(200 3625);
FORCEPROP 0 LAST SIG_NAME RST_PCIE_RISER1_PERST_R_N
J 1
(-212 3635);
DISPLAY 0.617021 (-212 3635);
PAINT ORANGE (-212 3635);
FORCEPROP 2 LASTPROP $XRERR UNIQUE?
J 0
(-452 3635);
DISPLAY 0.638298 (-452 3635);
PAINT MONO (-452 3635);
DISPLAY INVISIBLE (-452 3635);
WIRE 16 -1 (800 3675)(2275 3675);
FORCEPROP 0 LAST SIG_NAME FM_PE_SLOTX24_WAKE_N
J 2
(1875 3685);
DISPLAY 0.617021 (1875 3685);
PAINT ORANGE (1875 3685);
WIRE 16 -1 (-1500 3675)(200 3675);
FORCEPROP 0 LAST SIG_NAME FM_PRSNT_2_1_N
J 0
(-1375 3685);
DISPLAY 0.617021 (-1375 3685);
PAINT ORANGE (-1375 3685);
WIRE 16 -1 (200 3875)(-1475 3875);
FORCEPROP 0 LAST SIG_NAME FM_SLT_CFG0
J 0
(-1310 3885);
DISPLAY 0.617021 (-1310 3885);
PAINT ORANGE (-1310 3885);
WIRE 16 -1 (800 3975)(2800 3975);
FORCEPROP 0 LAST SIG_NAME IRQ_OOB_MGMT_RISER_ALERT_N
J 2
(2800 3985);
DISPLAY 0.617021 (2800 3985);
PAINT ORANGE (2800 3985);
WIRE 16 -1 (800 3425)(2250 3425);
FORCEPROP 0 LAST SIG_NAME CLK_100M_PCH_SLOTX24_S4_DN
J 0
(1290 3435);
DISPLAY 0.617021 (1290 3435);
PAINT ORANGE (1290 3435);
WIRE 16 -1 (800 3925)(2800 3925);
FORCEPROP 0 LAST SIG_NAME FM_SLT_CFG1
J 2
(2800 3935);
DISPLAY 0.617021 (2800 3935);
PAINT ORANGE (2800 3935);
WIRE 16 -1 (800 3875)(2600 3875);
FORCEPROP 0 LAST SIG_NAME FM_PWRBRK_SLOT_N
J 2
(2800 3885);
DISPLAY 0.617021 (2800 3885);
PAINT ORANGE (2800 3885);
WIRE 16 -1 (2600 3875)(2800 3875);
WIRE 16 -1 (2600 3775)(2600 3875);
WIRE 16 -1 (2475 3775)(2600 3775);
WIRE 16 -1 (800 2275)(1300 2275);
WIRE 16 -1 (-500 1925)(200 1925);
WIRE 16 -1 (-500 2075)(200 2075);
WIRE 16 -1 (-500 2225)(200 2225);
WIRE 16 -1 (-500 2375)(200 2375);
WIRE 16 -1 (200 3075)(-500 3075);
WIRE 16 -1 (800 3325)(2250 3325);
FORCEPROP 0 LAST SIG_NAME CLK_100M_PCH_SLOTX24_S1_DP
J 0
(1415 3335);
DISPLAY 0.617021 (1415 3335);
PAINT ORANGE (1415 3335);
WIRE 16 -1 (-1475 3975)(200 3975);
FORCEPROP 2 LAST SIG_NAME SMB_SLOTX24_STBY_LVC3_SDA_R2
J 2
(-675 3985);
DISPLAY 0.617021 (-675 3985);
PAINT ORANGE (-675 3985);
WIRE 16 -1 (-1475 3925)(200 3925);
FORCEPROP 2 LAST SIG_NAME SMB_SLOTX24_STBY_LVC3_SCL_R2
J 2
(-675 3935);
DISPLAY 0.617021 (-675 3935);
PAINT ORANGE (-675 3935);
WIRE 16 -1 (-1475 3625)(-725 3625);
FORCEPROP 0 LAST SIG_NAME RST_PCIE_RISER1_PERST_N
J 0
(-1375 3635);
DISPLAY 0.617021 (-1375 3635);
PAINT ORANGE (-1375 3635);
WIRE 16 -1 (2225 4200)(2225 3775);
WIRE 16 -1 (2275 3775)(2225 3775);
WIRE 16 -1 (2225 3775)(1925 3775);
FORCEPROP 0 LAST SIG_NAME FM_PWRBRK_N
J 0
(1940 3785);
DISPLAY 0.617021 (1940 3785);
PAINT ORANGE (1940 3785);
WIRE 16 -1 (-1925 4250)(-1250 4250);
WIRE 16 -1 (-1925 4250)(-1925 4350);
WIRE 16 -1 (-2300 4250)(-1925 4250);
FORCEPROP 2 LAST SIG_NAME SMB_SLOTX24_STBY_LVC3_SCL_R2
J 0
(-1910 4260);
DISPLAY 0.617021 (-1910 4260);
PAINT ORANGE (-1910 4260);
WIRE 16 -1 (-1925 4350)(-2300 4350);
WIRE 16 -1 (-1925 4500)(-1250 4500);
WIRE 16 -1 (-1925 4500)(-1925 4600);
WIRE 16 -1 (-2300 4500)(-1925 4500);
FORCEPROP 2 LAST SIG_NAME SMB_SLOTX24_STBY_LVC3_SDA_R2
J 0
(-1910 4510);
DISPLAY 0.617021 (-1910 4510);
PAINT ORANGE (-1910 4510);
WIRE 16 -1 (-1925 4600)(-2300 4600);
WIRE 16 -1 (-3125 4350)(-2500 4350);
FORCEPROP 2 LAST SIG_NAME SMB_SLOTX24_PCH_STBY_LVC3_SCL
J 0
(-3100 4360);
DISPLAY 0.617021 (-3100 4360);
PAINT ORANGE (-3100 4360);
WIRE 16 -1 (-3125 4250)(-2500 4250);
FORCEPROP 2 LAST SIG_NAME SMB_SLOTX24_BMC_STBY_LVC3_SCL
J 0
(-3100 4260);
DISPLAY 0.617021 (-3100 4260);
PAINT ORANGE (-3100 4260);
WIRE 16 -1 (-3125 4500)(-2500 4500);
FORCEPROP 2 LAST SIG_NAME SMB_SLOTX24_BMC_STBY_LVC3_SDA
J 0
(-3100 4510);
DISPLAY 0.617021 (-3100 4510);
PAINT ORANGE (-3100 4510);
WIRE 16 -1 (-3125 4600)(-2500 4600);
FORCEPROP 2 LAST SIG_NAME SMB_SLOTX24_PCH_STBY_LVC3_SDA
J 0
(-3100 4610);
DISPLAY 0.617021 (-3100 4610);
PAINT ORANGE (-3100 4610);
DOT 1 (-100 2275);
DOT 1 (-600 3075);
DOT 1 (1550 2975);
DOT 1 (1050 3075);
DOT 1 (1050 2525);
DOT 1 (1050 2775);
DOT 1 (1050 1825);
DOT 1 (1050 1925);
DOT 1 (1050 2375);
DOT 1 (1050 2225);
DOT 1 (1050 2925);
DOT 1 (1050 3225);
DOT 1 (-100 1825);
DOT 1 (-100 2575);
DOT 1 (-100 2125);
DOT 1 (-100 1975);
DOT 1 (-100 2825);
DOT 1 (-100 2425);
DOT 1 (-100 3125);
DOT 1 (1375 4325);
DOT 1 (1375 4275);
DOT 1 (1375 4225);
DOT 1 (1375 4175);
DOT 1 (1375 4125);
DOT 1 (2600 3875);
DOT 1 (2225 3775);
DOT 1 (1600 3825);
DOT 1 (1050 3725);
DOT 1 (1050 3525);
DOT 1 (1050 3375);
DOT 1 (1050 2675);
DOT 1 (1050 2075);
DOT 1 (-350 4325);
DOT 1 (-350 4275);
DOT 1 (-350 4225);
DOT 1 (-350 4175);
DOT 1 (-350 4125);
DOT 1 (-1925 4500);
DOT 1 (-1925 4250);
DOT 1 (-100 3425);
DOT 1 (-100 3575);
DOT 1 (-100 3275);
DOT 1 (-525 3825);
DOT 1 (-100 2975);
DOT 1 (-100 2725);
DOT 1 (-1950 1075);
DOT 1 (-2350 1550);
DOT 1 (-2875 1100);
DOT 1 (-2875 400);
DOT 1 (-3275 1575);
DOT 1 (-3275 850);
FORCENOTE
TP FAB1 MODIFY PCIE TOPOLOGY AND FOR ROUTING SMOOTH CHANGE CLOCK PIN DEFINE 1116
(-1200 1125) 0;
DISPLAY LEFT (-1200 1125);
DISPLAY 1.021277 (-1200 1125);
PAINT RED (-1200 1125);
FORCENOTE
ROOM=IO_SLOT
(-3516 223) 0;
DISPLAY LEFT (-3516 223);
DISPLAY 1.021277 (-3516 223);
PAINT PURPLE (-3516 223);
QUIT
